G04 ================== begin FILE IDENTIFICATION RECORD ==================*
G04 Layout Name:  15105-sa.brd*
G04 Film Name:    BSMD*
G04 File Format:  Gerber RS274X*
G04 File Origin:  Cadence Allegro 16.5-S056*
G04 Origin Date:  Wed Nov 16 02:01:46 2016*
G04 *
G04 Layer:  VIA CLASS/PASTEMASK_BOTTOM*
G04 Layer:  PIN/PASTEMASK_BOTTOM*
G04 Layer:  PACKAGE GEOMETRY/PASTEMASK_BOTTOM*
G04 Layer:  DRAWING FORMAT/LAYER_PCB_STORY*
G04 Layer:  DRAWING FORMAT/LAYER_PAST_B*
G04 Layer:  BOARD GEOMETRY/PANEL_OUTLINE*
G04 *
G04 Offset:    (0.00 0.00)*
G04 Mirror:    No*
G04 Mode:      Positive*
G04 Rotation:  0*
G04 FullContactRelief:  No*
G04 UndefLineWidth:     6.00*
G04 ================== end FILE IDENTIFICATION RECORD ====================*
%FSLAX35Y35*MOIN*%
%IR0*IPPOS*OFA0.00000B0.00000*MIA0B0*SFA1.00000B1.00000*%
%AMMACRO28*
4,1,40,.011,.007,
.011,-.007,
.010939,-.007695,
.010759,-.008368,
.010464,-.009,
.010064,-.009571,
.009571,-.010064,
.009,-.010464,
.008368,-.010759,
.007695,-.010939,
.007,-.011,
-.007,-.011,
-.007695,-.010939,
-.008368,-.010759,
-.009,-.010464,
-.009571,-.010064,
-.010064,-.009571,
-.010464,-.009,
-.010759,-.008368,
-.010939,-.007695,
-.011,-.007,
-.011,.007,
-.010939,.007695,
-.010759,.008368,
-.010464,.009,
-.010064,.009571,
-.009571,.010064,
-.009,.010464,
-.008368,.010759,
-.007695,.010939,
-.007,.011,
.007,.011,
.007695,.010939,
.008368,.010759,
.009,.010464,
.009571,.010064,
.010064,.009571,
.010464,.009,
.010759,.008368,
.010939,.007695,
.011,.007,
0.0*
%
%ADD28MACRO28*%
%AMMACRO37*
4,1,40,.013,-.017,
-.013,-.017,
-.013695,-.016939,
-.014368,-.016759,
-.015,-.016464,
-.015571,-.016064,
-.016064,-.015571,
-.016464,-.015,
-.016759,-.014368,
-.016939,-.013695,
-.017,-.013,
-.017,.013,
-.016939,.013695,
-.016759,.014368,
-.016464,.015,
-.016064,.015571,
-.015571,.016064,
-.015,.016464,
-.014368,.016759,
-.013695,.016939,
-.013,.017,
.013,.017,
.013695,.016939,
.014368,.016759,
.015,.016464,
.015571,.016064,
.016064,.015571,
.016464,.015,
.016759,.014368,
.016939,.013695,
.017,.013,
.017,-.013,
.016939,-.013695,
.016759,-.014368,
.016464,-.015,
.016064,-.015571,
.015571,-.016064,
.015,-.016464,
.014368,-.016759,
.013695,-.016939,
.013,-.017,
0.0*
%
%ADD37MACRO37*%
%AMMACRO19*
4,1,40,-.017,-.013,
-.017,.013,
-.016939,.013695,
-.016759,.014368,
-.016464,.015,
-.016064,.015571,
-.015571,.016064,
-.015,.016464,
-.014368,.016759,
-.013695,.016939,
-.013,.017,
.013,.017,
.013695,.016939,
.014368,.016759,
.015,.016464,
.015571,.016064,
.016064,.015571,
.016464,.015,
.016759,.014368,
.016939,.013695,
.017,.013,
.017,-.013,
.016939,-.013695,
.016759,-.014368,
.016464,-.015,
.016064,-.015571,
.015571,-.016064,
.015,-.016464,
.014368,-.016759,
.013695,-.016939,
.013,-.017,
-.013,-.017,
-.013695,-.016939,
-.014368,-.016759,
-.015,-.016464,
-.015571,-.016064,
-.016064,-.015571,
-.016464,-.015,
-.016759,-.014368,
-.016939,-.013695,
-.017,-.013,
0.0*
%
%ADD19MACRO19*%
%ADD12C,.04*%
%AMMACRO43*
4,1,40,-.007,-.004,
-.007,.004,
-.00697,.004347,
-.006879,.004684,
-.006732,.005,
-.006532,.005286,
-.006286,.005532,
-.006,.005732,
-.005684,.005879,
-.005347,.00597,
-.005,.006,
.005,.006,
.005347,.00597,
.005684,.005879,
.006,.005732,
.006286,.005532,
.006532,.005286,
.006732,.005,
.006879,.004684,
.00697,.004347,
.007,.004,
.007,-.004,
.00697,-.004347,
.006879,-.004684,
.006732,-.005,
.006532,-.005286,
.006286,-.005532,
.006,-.005732,
.005684,-.005879,
.005347,-.00597,
.005,-.006,
-.005,-.006,
-.005347,-.00597,
-.005684,-.005879,
-.006,-.005732,
-.006286,-.005532,
-.006532,-.005286,
-.006732,-.005,
-.006879,-.004684,
-.00697,-.004347,
-.007,-.004,
0.0*
%
%ADD43MACRO43*%
%AMMACRO44*
4,1,40,-.004,.007,
.004,.007,
.004347,.00697,
.004684,.006879,
.005,.006732,
.005286,.006532,
.005532,.006286,
.005732,.006,
.005879,.005684,
.00597,.005347,
.006,.005,
.006,-.005,
.00597,-.005347,
.005879,-.005684,
.005732,-.006,
.005532,-.006286,
.005286,-.006532,
.005,-.006732,
.004684,-.006879,
.004347,-.00697,
.004,-.007,
-.004,-.007,
-.004347,-.00697,
-.004684,-.006879,
-.005,-.006732,
-.005286,-.006532,
-.005532,-.006286,
-.005732,-.006,
-.005879,-.005684,
-.00597,-.005347,
-.006,-.005,
-.006,.005,
-.00597,.005347,
-.005879,.005684,
-.005732,.006,
-.005532,.006286,
-.005286,.006532,
-.005,.006732,
-.004684,.006879,
-.004347,.00697,
-.004,.007,
0.0*
%
%ADD44MACRO44*%
%ADD11C,.028*%
%AMMACRO40*
4,1,40,.0225,.007,
.022378,.008389,
.022018,.009736,
.021428,.011,
.020628,.012142,
.019642,.013128,
.0185,.013928,
.017236,.014518,
.015889,.014878,
.0145,.015,
-.0145,.015,
-.015889,.014878,
-.017236,.014518,
-.0185,.013928,
-.019642,.013128,
-.020628,.012142,
-.021428,.011,
-.022018,.009736,
-.022378,.008389,
-.0225,.007,
-.0225,-.007,
-.022378,-.008389,
-.022018,-.009736,
-.021428,-.011,
-.020628,-.012142,
-.019642,-.013128,
-.0185,-.013928,
-.017236,-.014518,
-.015889,-.014878,
-.0145,-.015,
.0145,-.015,
.015889,-.014878,
.017236,-.014518,
.0185,-.013928,
.019642,-.013128,
.020628,-.012142,
.021428,-.011,
.022018,-.009736,
.022378,-.008389,
.0225,-.007,
.0225,.007,
0.0*
%
%ADD40MACRO40*%
%AMMACRO23*
4,1,40,.007,-.011,
-.007,-.011,
-.007695,-.010939,
-.008368,-.010759,
-.009,-.010464,
-.009571,-.010064,
-.010064,-.009571,
-.010464,-.009,
-.010759,-.008368,
-.010939,-.007695,
-.011,-.007,
-.011,.007,
-.010939,.007695,
-.010759,.008368,
-.010464,.009,
-.010064,.009571,
-.009571,.010064,
-.009,.010464,
-.008368,.010759,
-.007695,.010939,
-.007,.011,
.007,.011,
.007695,.010939,
.008368,.010759,
.009,.010464,
.009571,.010064,
.010064,.009571,
.010464,.009,
.010759,.008368,
.010939,.007695,
.011,.007,
.011,-.007,
.010939,-.007695,
.010759,-.008368,
.010464,-.009,
.010064,-.009571,
.009571,-.010064,
.009,-.010464,
.008368,-.010759,
.007695,-.010939,
.007,-.011,
0.0*
%
%ADD23MACRO23*%
%AMMACRO17*
4,1,40,-.011,-.007,
-.011,.007,
-.010939,.007695,
-.010759,.008368,
-.010464,.009,
-.010064,.009571,
-.009571,.010064,
-.009,.010464,
-.008368,.010759,
-.007695,.010939,
-.007,.011,
.007,.011,
.007695,.010939,
.008368,.010759,
.009,.010464,
.009571,.010064,
.010064,.009571,
.010464,.009,
.010759,.008368,
.010939,.007695,
.011,.007,
.011,-.007,
.010939,-.007695,
.010759,-.008368,
.010464,-.009,
.010064,-.009571,
.009571,-.010064,
.009,-.010464,
.008368,-.010759,
.007695,-.010939,
.007,-.011,
-.007,-.011,
-.007695,-.010939,
-.008368,-.010759,
-.009,-.010464,
-.009571,-.010064,
-.010064,-.009571,
-.010464,-.009,
-.010759,-.008368,
-.010939,-.007695,
-.011,-.007,
0.0*
%
%ADD17MACRO17*%
%AMMACRO14*
4,1,40,-.012,-.008,
-.012,.008,
-.011939,.008695,
-.011759,.009368,
-.011464,.01,
-.011064,.010571,
-.010571,.011064,
-.01,.011464,
-.009368,.011759,
-.008695,.011939,
-.008,.012,
.008,.012,
.008695,.011939,
.009368,.011759,
.01,.011464,
.010571,.011064,
.011064,.010571,
.011464,.01,
.011759,.009368,
.011939,.008695,
.012,.008,
.012,-.008,
.011939,-.008695,
.011759,-.009368,
.011464,-.01,
.011064,-.010571,
.010571,-.011064,
.01,-.011464,
.009368,-.011759,
.008695,-.011939,
.008,-.012,
-.008,-.012,
-.008695,-.011939,
-.009368,-.011759,
-.01,-.011464,
-.010571,-.011064,
-.011064,-.010571,
-.011464,-.01,
-.011759,-.009368,
-.011939,-.008695,
-.012,-.008,
0.0*
%
%ADD14MACRO14*%
%AMMACRO26*
4,1,40,-.008,.012,
.008,.012,
.008695,.011939,
.009368,.011759,
.01,.011464,
.010571,.011064,
.011064,.010571,
.011464,.01,
.011759,.009368,
.011939,.008695,
.012,.008,
.012,-.008,
.011939,-.008695,
.011759,-.009368,
.011464,-.01,
.011064,-.010571,
.010571,-.011064,
.01,-.011464,
.009368,-.011759,
.008695,-.011939,
.008,-.012,
-.008,-.012,
-.008695,-.011939,
-.009368,-.011759,
-.01,-.011464,
-.010571,-.011064,
-.011064,-.010571,
-.011464,-.01,
-.011759,-.009368,
-.011939,-.008695,
-.012,-.008,
-.012,.008,
-.011939,.008695,
-.011759,.009368,
-.011464,.01,
-.011064,.010571,
-.010571,.011064,
-.01,.011464,
-.009368,.011759,
-.008695,.011939,
-.008,.012,
0.0*
%
%ADD26MACRO26*%
%AMMACRO36*
4,1,40,-.013,.017,
.013,.017,
.013695,.016939,
.014368,.016759,
.015,.016464,
.015571,.016064,
.016064,.015571,
.016464,.015,
.016759,.014368,
.016939,.013695,
.017,.013,
.017,-.013,
.016939,-.013695,
.016759,-.014368,
.016464,-.015,
.016064,-.015571,
.015571,-.016064,
.015,-.016464,
.014368,-.016759,
.013695,-.016939,
.013,-.017,
-.013,-.017,
-.013695,-.016939,
-.014368,-.016759,
-.015,-.016464,
-.015571,-.016064,
-.016064,-.015571,
-.016464,-.015,
-.016759,-.014368,
-.016939,-.013695,
-.017,-.013,
-.017,.013,
-.016939,.013695,
-.016759,.014368,
-.016464,.015,
-.016064,.015571,
-.015571,.016064,
-.015,.016464,
-.014368,.016759,
-.013695,.016939,
-.013,.017,
0.0*
%
%ADD36MACRO36*%
%AMMACRO47*
4,1,40,.017,.013,
.017,-.013,
.016939,-.013695,
.016759,-.014368,
.016464,-.015,
.016064,-.015571,
.015571,-.016064,
.015,-.016464,
.014368,-.016759,
.013695,-.016939,
.013,-.017,
-.013,-.017,
-.013695,-.016939,
-.014368,-.016759,
-.015,-.016464,
-.015571,-.016064,
-.016064,-.015571,
-.016464,-.015,
-.016759,-.014368,
-.016939,-.013695,
-.017,-.013,
-.017,.013,
-.016939,.013695,
-.016759,.014368,
-.016464,.015,
-.016064,.015571,
-.015571,.016064,
-.015,.016464,
-.014368,.016759,
-.013695,.016939,
-.013,.017,
.013,.017,
.013695,.016939,
.014368,.016759,
.015,.016464,
.015571,.016064,
.016064,.015571,
.016464,.015,
.016759,.014368,
.016939,.013695,
.017,.013,
0.0*
%
%ADD47MACRO47*%
%AMMACRO24*
4,1,40,.007,-.011,
-.007,-.011,
-.007695,-.010939,
-.008368,-.010759,
-.009,-.010464,
-.009571,-.010064,
-.010064,-.009571,
-.010464,-.009,
-.010759,-.008368,
-.010939,-.007695,
-.011,-.007,
-.011,.007,
-.010939,.007695,
-.010759,.008368,
-.010464,.009,
-.010064,.009571,
-.009571,.010064,
-.009,.010464,
-.008368,.010759,
-.007695,.010939,
-.007,.011,
.007,.011,
.007695,.010939,
.008368,.010759,
.009,.010464,
.009571,.010064,
.010064,.009571,
.010464,.009,
.010759,.008368,
.010939,.007695,
.011,.007,
.011,-.007,
.010939,-.007695,
.010759,-.008368,
.010464,-.009,
.010064,-.009571,
.009571,-.010064,
.009,-.010464,
.008368,-.010759,
.007695,-.010939,
.007,-.011,
0.0*
%
%ADD24MACRO24*%
%AMMACRO18*
4,1,40,-.011,-.007,
-.011,.007,
-.010939,.007695,
-.010759,.008368,
-.010464,.009,
-.010064,.009571,
-.009571,.010064,
-.009,.010464,
-.008368,.010759,
-.007695,.010939,
-.007,.011,
.007,.011,
.007695,.010939,
.008368,.010759,
.009,.010464,
.009571,.010064,
.010064,.009571,
.010464,.009,
.010759,.008368,
.010939,.007695,
.011,.007,
.011,-.007,
.010939,-.007695,
.010759,-.008368,
.010464,-.009,
.010064,-.009571,
.009571,-.010064,
.009,-.010464,
.008368,-.010759,
.007695,-.010939,
.007,-.011,
-.007,-.011,
-.007695,-.010939,
-.008368,-.010759,
-.009,-.010464,
-.009571,-.010064,
-.010064,-.009571,
-.010464,-.009,
-.010759,-.008368,
-.010939,-.007695,
-.011,-.007,
0.0*
%
%ADD18MACRO18*%
%AMMACRO15*
4,1,40,-.012,-.008,
-.012,.008,
-.011939,.008695,
-.011759,.009368,
-.011464,.01,
-.011064,.010571,
-.010571,.011064,
-.01,.011464,
-.009368,.011759,
-.008695,.011939,
-.008,.012,
.008,.012,
.008695,.011939,
.009368,.011759,
.01,.011464,
.010571,.011064,
.011064,.010571,
.011464,.01,
.011759,.009368,
.011939,.008695,
.012,.008,
.012,-.008,
.011939,-.008695,
.011759,-.009368,
.011464,-.01,
.011064,-.010571,
.010571,-.011064,
.01,-.011464,
.009368,-.011759,
.008695,-.011939,
.008,-.012,
-.008,-.012,
-.008695,-.011939,
-.009368,-.011759,
-.01,-.011464,
-.010571,-.011064,
-.011064,-.010571,
-.011464,-.01,
-.011759,-.009368,
-.011939,-.008695,
-.012,-.008,
0.0*
%
%ADD15MACRO15*%
%AMMACRO25*
4,1,40,-.008,.012,
.008,.012,
.008695,.011939,
.009368,.011759,
.01,.011464,
.010571,.011064,
.011064,.010571,
.011464,.01,
.011759,.009368,
.011939,.008695,
.012,.008,
.012,-.008,
.011939,-.008695,
.011759,-.009368,
.011464,-.01,
.011064,-.010571,
.010571,-.011064,
.01,-.011464,
.009368,-.011759,
.008695,-.011939,
.008,-.012,
-.008,-.012,
-.008695,-.011939,
-.009368,-.011759,
-.01,-.011464,
-.010571,-.011064,
-.011064,-.010571,
-.011464,-.01,
-.011759,-.009368,
-.011939,-.008695,
-.012,-.008,
-.012,.008,
-.011939,.008695,
-.011759,.009368,
-.011464,.01,
-.011064,.010571,
-.010571,.011064,
-.01,.011464,
-.009368,.011759,
-.008695,.011939,
-.008,.012,
0.0*
%
%ADD25MACRO25*%
%AMMACRO35*
4,1,40,-.013,.017,
.013,.017,
.013695,.016939,
.014368,.016759,
.015,.016464,
.015571,.016064,
.016064,.015571,
.016464,.015,
.016759,.014368,
.016939,.013695,
.017,.013,
.017,-.013,
.016939,-.013695,
.016759,-.014368,
.016464,-.015,
.016064,-.015571,
.015571,-.016064,
.015,-.016464,
.014368,-.016759,
.013695,-.016939,
.013,-.017,
-.013,-.017,
-.013695,-.016939,
-.014368,-.016759,
-.015,-.016464,
-.015571,-.016064,
-.016064,-.015571,
-.016464,-.015,
-.016759,-.014368,
-.016939,-.013695,
-.017,-.013,
-.017,.013,
-.016939,.013695,
-.016759,.014368,
-.016464,.015,
-.016064,.015571,
-.015571,.016064,
-.015,.016464,
-.014368,.016759,
-.013695,.016939,
-.013,.017,
0.0*
%
%ADD35MACRO35*%
%AMMACRO48*
4,1,40,.017,.013,
.017,-.013,
.016939,-.013695,
.016759,-.014368,
.016464,-.015,
.016064,-.015571,
.015571,-.016064,
.015,-.016464,
.014368,-.016759,
.013695,-.016939,
.013,-.017,
-.013,-.017,
-.013695,-.016939,
-.014368,-.016759,
-.015,-.016464,
-.015571,-.016064,
-.016064,-.015571,
-.016464,-.015,
-.016759,-.014368,
-.016939,-.013695,
-.017,-.013,
-.017,.013,
-.016939,.013695,
-.016759,.014368,
-.016464,.015,
-.016064,.015571,
-.015571,.016064,
-.015,.016464,
-.014368,.016759,
-.013695,.016939,
-.013,.017,
.013,.017,
.013695,.016939,
.014368,.016759,
.015,.016464,
.015571,.016064,
.016064,.015571,
.016464,.015,
.016759,.014368,
.016939,.013695,
.017,.013,
0.0*
%
%ADD48MACRO48*%
%ADD46R,.04X.014*%
%ADD33R,.04X.016*%
%ADD34R,.016X.04*%
%AMMACRO45*
4,1,40,.004,-.007,
-.004,-.007,
-.004347,-.00697,
-.004684,-.006879,
-.005,-.006732,
-.005286,-.006532,
-.005532,-.006286,
-.005732,-.006,
-.005879,-.005684,
-.00597,-.005347,
-.006,-.005,
-.006,.005,
-.00597,.005347,
-.005879,.005684,
-.005732,.006,
-.005532,.006286,
-.005286,.006532,
-.005,.006732,
-.004684,.006879,
-.004347,.00697,
-.004,.007,
.004,.007,
.004347,.00697,
.004684,.006879,
.005,.006732,
.005286,.006532,
.005532,.006286,
.005732,.006,
.005879,.005684,
.00597,.005347,
.006,.005,
.006,-.005,
.00597,-.005347,
.005879,-.005684,
.005732,-.006,
.005532,-.006286,
.005286,-.006532,
.005,-.006732,
.004684,-.006879,
.004347,-.00697,
.004,-.007,
0.0*
%
%ADD45MACRO45*%
%AMMACRO42*
4,1,40,.007,.004,
.007,-.004,
.00697,-.004347,
.006879,-.004684,
.006732,-.005,
.006532,-.005286,
.006286,-.005532,
.006,-.005732,
.005684,-.005879,
.005347,-.00597,
.005,-.006,
-.005,-.006,
-.005347,-.00597,
-.005684,-.005879,
-.006,-.005732,
-.006286,-.005532,
-.006532,-.005286,
-.006732,-.005,
-.006879,-.004684,
-.00697,-.004347,
-.007,-.004,
-.007,.004,
-.00697,.004347,
-.006879,.004684,
-.006732,.005,
-.006532,.005286,
-.006286,.005532,
-.006,.005732,
-.005684,.005879,
-.005347,.00597,
-.005,.006,
.005,.006,
.005347,.00597,
.005684,.005879,
.006,.005732,
.006286,.005532,
.006532,.005286,
.006732,.005,
.006879,.004684,
.00697,.004347,
.007,.004,
0.0*
%
%ADD42MACRO42*%
%ADD10R,.045X.055*%
%ADD39R,.016X.048*%
%ADD16R,.055X.045*%
%AMMACRO49*
4,1,40,-.007,.0225,
-.008389,.022378,
-.009736,.022018,
-.011,.021428,
-.012142,.020628,
-.013128,.019642,
-.013928,.0185,
-.014518,.017236,
-.014878,.015889,
-.015,.0145,
-.015,-.0145,
-.014878,-.015889,
-.014518,-.017236,
-.013928,-.0185,
-.013128,-.019642,
-.012142,-.020628,
-.011,-.021428,
-.009736,-.022018,
-.008389,-.022378,
-.007,-.0225,
.007,-.0225,
.008389,-.022378,
.009736,-.022018,
.011,-.021428,
.012142,-.020628,
.013128,-.019642,
.013928,-.0185,
.014518,-.017236,
.014878,-.015889,
.015,-.0145,
.015,.0145,
.014878,.015889,
.014518,.017236,
.013928,.0185,
.013128,.019642,
.012142,.020628,
.011,.021428,
.009736,.022018,
.008389,.022378,
.007,.0225,
-.007,.0225,
0.0*
%
%ADD49MACRO49*%
%AMMACRO41*
4,1,40,-.012,-.024,
.012,-.024,
.013389,-.023878,
.014736,-.023518,
.016,-.022928,
.017142,-.022128,
.018128,-.021142,
.018928,-.02,
.019518,-.018736,
.019878,-.017389,
.02,-.016,
.02,.016,
.019878,.017389,
.019518,.018736,
.018928,.02,
.018128,.021142,
.017142,.022128,
.016,.022928,
.014736,.023518,
.013389,.023878,
.012,.024,
-.012,.024,
-.013389,.023878,
-.014736,.023518,
-.016,.022928,
-.017142,.022128,
-.018128,.021142,
-.018928,.02,
-.019518,.018736,
-.019878,.017389,
-.02,.016,
-.02,-.016,
-.019878,-.017389,
-.019518,-.018736,
-.018928,-.02,
-.018128,-.021142,
-.017142,-.022128,
-.016,-.022928,
-.014736,-.023518,
-.013389,-.023878,
-.012,-.024,
0.0*
%
%ADD41MACRO41*%
%AMMACRO31*
4,1,40,.012,.008,
.012,-.008,
.011939,-.008695,
.011759,-.009368,
.011464,-.01,
.011064,-.010571,
.010571,-.011064,
.01,-.011464,
.009368,-.011759,
.008695,-.011939,
.008,-.012,
-.008,-.012,
-.008695,-.011939,
-.009368,-.011759,
-.01,-.011464,
-.010571,-.011064,
-.011064,-.010571,
-.011464,-.01,
-.011759,-.009368,
-.011939,-.008695,
-.012,-.008,
-.012,.008,
-.011939,.008695,
-.011759,.009368,
-.011464,.01,
-.011064,.010571,
-.010571,.011064,
-.01,.011464,
-.009368,.011759,
-.008695,.011939,
-.008,.012,
.008,.012,
.008695,.011939,
.009368,.011759,
.01,.011464,
.010571,.011064,
.011064,.010571,
.011464,.01,
.011759,.009368,
.011939,.008695,
.012,.008,
0.0*
%
%ADD31MACRO31*%
%AMMACRO29*
4,1,40,.008,-.012,
-.008,-.012,
-.008695,-.011939,
-.009368,-.011759,
-.01,-.011464,
-.010571,-.011064,
-.011064,-.010571,
-.011464,-.01,
-.011759,-.009368,
-.011939,-.008695,
-.012,-.008,
-.012,.008,
-.011939,.008695,
-.011759,.009368,
-.011464,.01,
-.011064,.010571,
-.010571,.011064,
-.01,.011464,
-.009368,.011759,
-.008695,.011939,
-.008,.012,
.008,.012,
.008695,.011939,
.009368,.011759,
.01,.011464,
.010571,.011064,
.011064,.010571,
.011464,.01,
.011759,.009368,
.011939,.008695,
.012,.008,
.012,-.008,
.011939,-.008695,
.011759,-.009368,
.011464,-.01,
.011064,-.010571,
.010571,-.011064,
.01,-.011464,
.009368,-.011759,
.008695,-.011939,
.008,-.012,
0.0*
%
%ADD29MACRO29*%
%AMMACRO21*
4,1,40,-.007,.011,
.007,.011,
.007695,.010939,
.008368,.010759,
.009,.010464,
.009571,.010064,
.010064,.009571,
.010464,.009,
.010759,.008368,
.010939,.007695,
.011,.007,
.011,-.007,
.010939,-.007695,
.010759,-.008368,
.010464,-.009,
.010064,-.009571,
.009571,-.010064,
.009,-.010464,
.008368,-.010759,
.007695,-.010939,
.007,-.011,
-.007,-.011,
-.007695,-.010939,
-.008368,-.010759,
-.009,-.010464,
-.009571,-.010064,
-.010064,-.009571,
-.010464,-.009,
-.010759,-.008368,
-.010939,-.007695,
-.011,-.007,
-.011,.007,
-.010939,.007695,
-.010759,.008368,
-.010464,.009,
-.010064,.009571,
-.009571,.010064,
-.009,.010464,
-.008368,.010759,
-.007695,.010939,
-.007,.011,
0.0*
%
%ADD21MACRO21*%
%AMMACRO27*
4,1,40,.011,.007,
.011,-.007,
.010939,-.007695,
.010759,-.008368,
.010464,-.009,
.010064,-.009571,
.009571,-.010064,
.009,-.010464,
.008368,-.010759,
.007695,-.010939,
.007,-.011,
-.007,-.011,
-.007695,-.010939,
-.008368,-.010759,
-.009,-.010464,
-.009571,-.010064,
-.010064,-.009571,
-.010464,-.009,
-.010759,-.008368,
-.010939,-.007695,
-.011,-.007,
-.011,.007,
-.010939,.007695,
-.010759,.008368,
-.010464,.009,
-.010064,.009571,
-.009571,.010064,
-.009,.010464,
-.008368,.010759,
-.007695,.010939,
-.007,.011,
.007,.011,
.007695,.010939,
.008368,.010759,
.009,.010464,
.009571,.010064,
.010064,.009571,
.010464,.009,
.010759,.008368,
.010939,.007695,
.011,.007,
0.0*
%
%ADD27MACRO27*%
%AMMACRO38*
4,1,40,.013,-.017,
-.013,-.017,
-.013695,-.016939,
-.014368,-.016759,
-.015,-.016464,
-.015571,-.016064,
-.016064,-.015571,
-.016464,-.015,
-.016759,-.014368,
-.016939,-.013695,
-.017,-.013,
-.017,.013,
-.016939,.013695,
-.016759,.014368,
-.016464,.015,
-.016064,.015571,
-.015571,.016064,
-.015,.016464,
-.014368,.016759,
-.013695,.016939,
-.013,.017,
.013,.017,
.013695,.016939,
.014368,.016759,
.015,.016464,
.015571,.016064,
.016064,.015571,
.016464,.015,
.016759,.014368,
.016939,.013695,
.017,.013,
.017,-.013,
.016939,-.013695,
.016759,-.014368,
.016464,-.015,
.016064,-.015571,
.015571,-.016064,
.015,-.016464,
.014368,-.016759,
.013695,-.016939,
.013,-.017,
0.0*
%
%ADD38MACRO38*%
%AMMACRO20*
4,1,40,-.017,-.013,
-.017,.013,
-.016939,.013695,
-.016759,.014368,
-.016464,.015,
-.016064,.015571,
-.015571,.016064,
-.015,.016464,
-.014368,.016759,
-.013695,.016939,
-.013,.017,
.013,.017,
.013695,.016939,
.014368,.016759,
.015,.016464,
.015571,.016064,
.016064,.015571,
.016464,.015,
.016759,.014368,
.016939,.013695,
.017,.013,
.017,-.013,
.016939,-.013695,
.016759,-.014368,
.016464,-.015,
.016064,-.015571,
.015571,-.016064,
.015,-.016464,
.014368,-.016759,
.013695,-.016939,
.013,-.017,
-.013,-.017,
-.013695,-.016939,
-.014368,-.016759,
-.015,-.016464,
-.015571,-.016064,
-.016064,-.015571,
-.016464,-.015,
-.016759,-.014368,
-.016939,-.013695,
-.017,-.013,
0.0*
%
%ADD20MACRO20*%
%AMMACRO32*
4,1,40,.012,.008,
.012,-.008,
.011939,-.008695,
.011759,-.009368,
.011464,-.01,
.011064,-.010571,
.010571,-.011064,
.01,-.011464,
.009368,-.011759,
.008695,-.011939,
.008,-.012,
-.008,-.012,
-.008695,-.011939,
-.009368,-.011759,
-.01,-.011464,
-.010571,-.011064,
-.011064,-.010571,
-.011464,-.01,
-.011759,-.009368,
-.011939,-.008695,
-.012,-.008,
-.012,.008,
-.011939,.008695,
-.011759,.009368,
-.011464,.01,
-.011064,.010571,
-.010571,.011064,
-.01,.011464,
-.009368,.011759,
-.008695,.011939,
-.008,.012,
.008,.012,
.008695,.011939,
.009368,.011759,
.01,.011464,
.010571,.011064,
.011064,.010571,
.011464,.01,
.011759,.009368,
.011939,.008695,
.012,.008,
0.0*
%
%ADD32MACRO32*%
%AMMACRO30*
4,1,40,.008,-.012,
-.008,-.012,
-.008695,-.011939,
-.009368,-.011759,
-.01,-.011464,
-.010571,-.011064,
-.011064,-.010571,
-.011464,-.01,
-.011759,-.009368,
-.011939,-.008695,
-.012,-.008,
-.012,.008,
-.011939,.008695,
-.011759,.009368,
-.011464,.01,
-.011064,.010571,
-.010571,.011064,
-.01,.011464,
-.009368,.011759,
-.008695,.011939,
-.008,.012,
.008,.012,
.008695,.011939,
.009368,.011759,
.01,.011464,
.010571,.011064,
.011064,.010571,
.011464,.01,
.011759,.009368,
.011939,.008695,
.012,.008,
.012,-.008,
.011939,-.008695,
.011759,-.009368,
.011464,-.01,
.011064,-.010571,
.010571,-.011064,
.01,-.011464,
.009368,-.011759,
.008695,-.011939,
.008,-.012,
0.0*
%
%ADD30MACRO30*%
%AMMACRO22*
4,1,40,-.007,.011,
.007,.011,
.007695,.010939,
.008368,.010759,
.009,.010464,
.009571,.010064,
.010064,.009571,
.010464,.009,
.010759,.008368,
.010939,.007695,
.011,.007,
.011,-.007,
.010939,-.007695,
.010759,-.008368,
.010464,-.009,
.010064,-.009571,
.009571,-.010064,
.009,-.010464,
.008368,-.010759,
.007695,-.010939,
.007,-.011,
-.007,-.011,
-.007695,-.010939,
-.008368,-.010759,
-.009,-.010464,
-.009571,-.010064,
-.010064,-.009571,
-.010464,-.009,
-.010759,-.008368,
-.010939,-.007695,
-.011,-.007,
-.011,.007,
-.010939,.007695,
-.010759,.008368,
-.010464,.009,
-.010064,.009571,
-.009571,.010064,
-.009,.010464,
-.008368,.010759,
-.007695,.010939,
-.007,.011,
0.0*
%
%ADD22MACRO22*%
%ADD50C,.02*%
%ADD51C,.006*%
G75*
%LPD*%
G75*
G54D10*
X31300Y268800D03*
X38900D03*
X39700Y278500D03*
X32100D03*
X39800Y308300D03*
X32200D03*
X57100Y315100D03*
X64700D03*
X98020Y307120D03*
X89776Y291298D03*
X82176D03*
X105620Y307120D03*
X248700Y177000D03*
X256300D03*
X267700Y166000D03*
X248700Y185000D03*
X256300D03*
X275300Y166000D03*
X570063Y253608D03*
X592763Y256608D03*
X600363D03*
X577663Y253608D03*
X628863Y254608D03*
X621263D03*
X628600Y362100D03*
X621000D03*
X930300Y267000D03*
X922700D03*
X930300Y275000D03*
X922700D03*
X930300Y283000D03*
X922700D03*
X965200Y267500D03*
X972800D03*
X965200Y275500D03*
X972800D03*
X965200Y283500D03*
X972800D03*
X1311200Y250500D03*
X1346300Y240000D03*
X1338700D03*
X1346300Y248000D03*
X1338700D03*
X1318800Y250500D03*
G54D20*
X67400Y274900D03*
X72100D03*
X228500Y161800D03*
X276200Y159700D03*
G54D11*
X29000Y616000D03*
X54903Y447003D03*
X68100Y264700D03*
X98588Y281650D03*
X96304Y287616D03*
X70124Y279374D03*
X78500Y277900D03*
X92907Y280765D03*
X67796Y470042D03*
X86363Y479563D03*
X95742Y490870D03*
X86787Y494553D03*
X66854Y507824D03*
X68600Y494400D03*
X88700Y524900D03*
X88565Y532410D03*
X70515Y538726D03*
X68567Y531405D03*
X88278Y548853D03*
X73100Y553100D03*
X88338Y553955D03*
X85500Y807700D03*
X116906Y283244D03*
X111000Y324200D03*
X102457Y347690D03*
X132204Y434627D03*
X114818Y433528D03*
X128280Y476120D03*
X105728Y471628D03*
X103500Y465026D03*
X127142Y459404D03*
X107889Y457989D03*
X116204Y474504D03*
X131718Y498682D03*
X128450Y481470D03*
X117771Y499896D03*
X117867Y488950D03*
X128100Y507700D03*
X100063Y498972D03*
X103055Y503417D03*
X106818Y513350D03*
X99221Y509408D03*
X106037Y507711D03*
X106900Y488923D03*
X114000Y483700D03*
X105555Y483119D03*
X116439Y547024D03*
X102075Y529701D03*
X130200Y517000D03*
X106575Y518876D03*
X107341Y528856D03*
X99768Y518303D03*
X113757Y520886D03*
X105136Y535172D03*
X113900Y533666D03*
X102326Y540322D03*
X100270Y545196D03*
X122048Y541693D03*
X115100Y541700D03*
X123100Y547800D03*
X100350Y550196D03*
X105851Y637000D03*
X120500Y697500D03*
X122167Y731990D03*
X99700Y732300D03*
X103800Y727700D03*
X110900Y779200D03*
X122200Y831700D03*
X134587Y443980D03*
X137136Y422798D03*
X165000Y468000D03*
X157500D03*
X139500Y466500D03*
X134500Y466000D03*
X157500Y458000D03*
Y463000D03*
X133440Y449150D03*
X132959Y460709D03*
X159434Y475345D03*
X133589Y477613D03*
X136272Y496478D03*
X137600Y501338D03*
X150100Y494700D03*
X164371Y494680D03*
X165864Y533933D03*
X143500Y622500D03*
X137194Y727551D03*
X164378Y778459D03*
X159774Y785777D03*
X164442Y802359D03*
X159838Y813369D03*
X148000Y833500D03*
X175430Y261054D03*
X173277Y315920D03*
X167423Y341376D03*
X188215Y333962D03*
X182855Y337950D03*
X176854Y332347D03*
X187361Y342183D03*
X181838Y332783D03*
X178692Y352383D03*
X197937Y384347D03*
X197713Y431418D03*
X199900Y420100D03*
X175317Y416683D03*
X181400Y415300D03*
X182000Y466000D03*
X177000D03*
X171000Y468000D03*
X169000Y463000D03*
Y458000D03*
X187928Y473629D03*
X179192Y471349D03*
X190675Y468551D03*
X181328Y460701D03*
X199880Y498149D03*
X198000Y493500D03*
X166608Y501664D03*
X184535Y502910D03*
X194148Y501205D03*
X187300Y486900D03*
X169514Y492829D03*
X199809Y485199D03*
X178000Y542000D03*
X173000Y547500D03*
X178000Y547000D03*
X167000Y545500D03*
X168599Y527221D03*
X173000Y542500D03*
X173618Y516881D03*
X181811Y524978D03*
X188978Y524513D03*
X185355Y537874D03*
X173000Y552500D03*
X193600Y569800D03*
X186416Y573231D03*
X193500Y628000D03*
X199379Y698698D03*
X171631Y722694D03*
X167027Y730499D03*
X199411Y721528D03*
X171729Y747695D03*
X199378Y752617D03*
X167125Y759093D03*
X199410Y790376D03*
X169840Y836660D03*
X174265Y828735D03*
X220384Y178059D03*
X215968Y389018D03*
X214888Y425445D03*
X221699Y428056D03*
X202469Y429873D03*
X205100Y413700D03*
X202185Y462653D03*
X204319Y479895D03*
X206487Y475373D03*
X218774Y452245D03*
X224548Y470077D03*
X206285Y457550D03*
X218425D03*
X223334Y458504D03*
X210828Y469403D03*
X205397Y489870D03*
X232600Y535000D03*
X201400Y532400D03*
X205000Y521500D03*
X217291Y524970D03*
X201900Y525500D03*
X222500Y514500D03*
X222700Y546500D03*
X206200Y530500D03*
X201429Y566997D03*
X222800Y562100D03*
X210510Y562800D03*
X203983Y706502D03*
X204015Y733445D03*
X204186Y762392D03*
X204014Y779192D03*
X217104Y796396D03*
X214649Y802351D03*
X212841Y807659D03*
X218937Y791063D03*
X249530Y132250D03*
X236807Y140322D03*
X236500Y147500D03*
X239500Y160500D03*
X266200Y243500D03*
X251700Y429200D03*
X241446Y452004D03*
X247661Y473600D03*
X247473Y455600D03*
X260500Y486800D03*
X259800Y492500D03*
X233701Y522611D03*
X262500Y532012D03*
X241521Y654021D03*
X248890Y708110D03*
X255968Y706032D03*
X249797Y701703D03*
X259633Y715867D03*
X260816Y710184D03*
X254212Y712288D03*
X267011Y718817D03*
X257728Y722272D03*
X263500Y748700D03*
X268500Y140500D03*
X273800Y240000D03*
X299800Y305500D03*
X285700Y578165D03*
X285900Y583165D03*
X285606Y588172D03*
X267540Y585155D03*
X273134Y593265D03*
X270430Y725738D03*
X279045Y729078D03*
X293738Y729123D03*
X299500Y736000D03*
X283004Y739009D03*
X278500Y768500D03*
X290830Y768755D03*
X285000Y757000D03*
X297500D03*
X275900Y755951D03*
X334755Y141755D03*
X321708Y371677D03*
X321454Y351196D03*
X330000Y496213D03*
X329913Y714413D03*
X321500Y706500D03*
X328331Y708331D03*
X306471Y722269D03*
X318162Y729949D03*
X302000Y730500D03*
X332500Y739500D03*
X315531Y734807D03*
X307400Y765738D03*
X327373Y765761D03*
X317453Y752192D03*
X303000Y756500D03*
X329575Y758230D03*
X315100Y757400D03*
X359061Y335014D03*
X338725Y481514D03*
X357500Y561500D03*
X362533Y808033D03*
X364759Y815759D03*
X360807Y799807D03*
X417988Y813088D03*
X449500Y85000D03*
X480533Y363869D03*
X475782Y371442D03*
X480960Y388964D03*
X476010Y399971D03*
X485724Y779993D03*
X495307Y763932D03*
X495824Y756449D03*
X487949Y760641D03*
X487744Y752436D03*
X498500Y809000D03*
X477000Y804000D03*
X481600Y796800D03*
X496000Y788000D03*
X492278Y820500D03*
X481000Y818000D03*
X520910Y124390D03*
X515220Y126440D03*
X531900Y155800D03*
X523242Y196195D03*
X529154Y255014D03*
X525785Y362796D03*
X537000Y700500D03*
X504169Y774643D03*
X518328Y781467D03*
X531500Y778600D03*
X514298Y784745D03*
X516500Y808000D03*
X530012Y803025D03*
X510500Y808500D03*
X527948Y809620D03*
X508700Y784700D03*
X528500Y788000D03*
X521000Y820000D03*
X504241Y820278D03*
X532506Y820000D03*
X538158Y156255D03*
X546391Y208718D03*
X548656Y229162D03*
X568663Y288740D03*
X554300Y368300D03*
X545500Y783500D03*
X537500Y817000D03*
X546200Y799800D03*
X546000Y793000D03*
X577336Y125424D03*
X573055Y121869D03*
X603163Y220858D03*
X580200Y224000D03*
X596500Y226100D03*
X591861Y232396D03*
X576200Y238400D03*
X602463Y284008D03*
X616614Y123871D03*
X611642Y123340D03*
X607812Y149121D03*
X612812Y149084D03*
X609777Y158860D03*
X632900Y339700D03*
X655000Y125360D03*
X649692Y125160D03*
X643518Y125457D03*
X656500Y139300D03*
X670465Y266585D03*
X646600Y363400D03*
X643538Y803500D03*
X641000Y816500D03*
X646800Y811500D03*
X691100Y168238D03*
X691400Y310000D03*
X691487Y798987D03*
X693243Y804943D03*
X688212Y791912D03*
X695049Y811349D03*
X731800Y166000D03*
X706937Y203092D03*
X736100Y197200D03*
X741600Y34439D03*
X751871Y175034D03*
X755200Y223800D03*
X756200Y299800D03*
X799459Y772175D03*
X815976Y32276D03*
X838881Y27195D03*
X833246Y24741D03*
X826141Y21594D03*
X819052Y23633D03*
X811937Y41381D03*
X827727Y43554D03*
X825500Y697000D03*
X817405Y779905D03*
X808584Y776584D03*
X831500Y774750D03*
X836300Y783300D03*
X865600Y-1700D03*
X853500Y-2100D03*
X863500Y28000D03*
X848545Y24961D03*
X843545Y25012D03*
X871800Y15309D03*
X850900Y16200D03*
X848623Y74557D03*
X865004Y49379D03*
X866000Y82500D03*
X859000Y86500D03*
X866919Y92419D03*
X858821Y75500D03*
X853500Y257000D03*
X850799Y743301D03*
X872500Y728500D03*
X844500Y750000D03*
X851500Y753000D03*
X872617Y750235D03*
X864366Y758100D03*
X856576Y767771D03*
X867640Y761880D03*
X861500Y797000D03*
X853500Y817362D03*
X874033Y797475D03*
X864000Y814500D03*
X858020Y786180D03*
X840960Y785260D03*
X864147Y785093D03*
X863500Y823338D03*
X845500Y820500D03*
X878320Y4350D03*
X888200Y30500D03*
X882429Y54551D03*
X905488Y48573D03*
X902169Y97919D03*
X894533Y100933D03*
X875070Y104670D03*
X894850Y112060D03*
X903920Y137780D03*
X898000Y117000D03*
X908020Y153340D03*
X903937Y145666D03*
X903970Y157478D03*
X895232Y186459D03*
X885000Y297000D03*
X898500Y499000D03*
X880889Y613611D03*
X875252Y623748D03*
X896000Y686000D03*
X884700Y708000D03*
X892100Y694000D03*
X881200Y713500D03*
X888550Y702000D03*
X887500Y731500D03*
X879815Y742296D03*
X886800Y759500D03*
X878578Y761050D03*
X899800Y753000D03*
X898566Y761430D03*
X886500Y765000D03*
X890500Y796638D03*
X888000Y789000D03*
X874800Y786800D03*
X900000Y786000D03*
X882590Y787130D03*
X925300Y47100D03*
X910945Y49234D03*
X938600Y99500D03*
X915315Y97565D03*
X939384Y106513D03*
X915926Y102676D03*
X908676Y99926D03*
X911800Y141750D03*
X919650Y137800D03*
X915750Y133900D03*
X912200Y112300D03*
X940051Y113222D03*
X934700Y114200D03*
X911817Y149617D03*
X911820Y157500D03*
X915790Y161420D03*
X919685Y149606D03*
X915750Y145650D03*
Y153500D03*
X919700Y157500D03*
X927559Y153543D03*
X920800Y143400D03*
X923620Y161450D03*
X914700Y281100D03*
X947000Y71500D03*
X960244Y64888D03*
X952900Y98900D03*
X967263Y100000D03*
Y105000D03*
X975004Y105097D03*
Y100097D03*
X960500Y105000D03*
X953000Y104500D03*
X944300Y98500D03*
X960500Y100000D03*
X960000Y95000D03*
X959793Y75788D03*
X970866Y137795D03*
X974803Y141732D03*
X949700Y112900D03*
X959055Y129921D03*
X974803Y133858D03*
X966929D03*
X955118Y141732D03*
X959055Y137795D03*
X949987Y131571D03*
X948058Y136248D03*
X974803Y157480D03*
X970866Y161417D03*
X955118Y149606D03*
X959055Y145669D03*
X970866Y153543D03*
X966929Y149606D03*
X970866Y145669D03*
X959055Y161417D03*
Y153543D03*
X962992Y157480D03*
X951181Y153543D03*
X945030Y156121D03*
X944300Y271000D03*
X968500Y383500D03*
X1005774Y31854D03*
X1005750Y19788D03*
X980000Y44000D03*
X996251Y45701D03*
X982000Y100000D03*
Y105000D03*
X994700Y108600D03*
X982677Y141732D03*
X990551Y133858D03*
X982677D03*
X984760Y112189D03*
X982700Y149600D03*
X978740Y153543D03*
X982632Y157480D03*
X978740Y161417D03*
X991300Y145800D03*
X991608Y153979D03*
X1000000Y187000D03*
X980000Y281300D03*
X1035323Y-758D03*
X1031991Y22473D03*
X1036989Y22307D03*
X1036013Y27318D03*
X1033971Y34914D03*
X1031474Y9728D03*
X1020676Y53563D03*
X1037815Y104700D03*
X1016500Y101050D03*
X1041249Y112300D03*
X1030883Y112238D03*
X1066272Y1949D03*
X1044391Y-1209D03*
X1069394Y13018D03*
X1052744Y48446D03*
X1072167Y49782D03*
X1069889Y45154D03*
X1048000Y815000D03*
X1088503Y3601D03*
X1085500Y-3000D03*
X1086715Y27686D03*
X1080017Y27022D03*
X1086500Y280000D03*
X1167000Y254000D03*
X1171747Y814500D03*
X1176738Y806500D03*
X1168607Y834500D03*
X1198134Y420766D03*
X1179723Y418777D03*
X1242500Y645000D03*
X1236000Y814000D03*
X1269500Y161000D03*
X1261000Y230000D03*
X1255000Y323000D03*
X1274030Y339470D03*
X1264820Y356000D03*
X1273500Y406500D03*
X1270000Y487500D03*
X1269000Y609000D03*
X1284505Y308395D03*
X1280836Y338164D03*
X1295000Y338000D03*
X1307500Y340500D03*
X1298500Y376500D03*
X1312839Y384339D03*
X1305500Y379500D03*
X1305432Y622932D03*
X1296264Y645191D03*
X1291800Y637751D03*
X1292000Y667000D03*
X1298017Y684000D03*
X1303709Y688956D03*
X1298000Y703500D03*
X1298500Y734838D03*
X1305650Y725500D03*
X1295714Y716714D03*
X1327736Y271358D03*
X1325500Y289400D03*
X1314422Y638422D03*
X1318117Y680886D03*
X1343000Y681000D03*
X1331000Y658200D03*
X1330000Y672162D03*
X1333052Y686020D03*
X1319500Y690000D03*
X1337338Y712709D03*
X1322300Y713500D03*
X1315000Y714000D03*
X1333639Y716074D03*
X1317500Y695000D03*
X1334195Y694005D03*
X1318228Y725500D03*
X1330000Y724500D03*
X1344237Y721833D03*
X1342000Y726500D03*
X1338128Y738000D03*
X1320500Y719888D03*
X1324000Y763500D03*
X1340500Y751500D03*
X1379473Y163528D03*
X1368540Y169284D03*
X1353908Y194867D03*
X1365804Y189733D03*
X1370000Y216500D03*
X1354500Y271000D03*
X1355209Y263791D03*
X1364000Y299500D03*
X1351500Y671200D03*
X1355000Y716000D03*
X1352000Y708500D03*
Y698000D03*
X1353500Y758500D03*
X1383164Y168943D03*
G54D30*
X120351Y626636D03*
X126851D03*
X143217Y498160D03*
X156862Y498211D03*
X152916Y497936D03*
X146960Y498030D03*
X165851Y624136D03*
X137551Y622136D03*
X149851Y624136D03*
X155851D03*
X160851D03*
X217000Y534700D03*
X221000Y525700D03*
X500332Y130164D03*
X493245Y130025D03*
X489680Y130005D03*
X503827Y130104D03*
X563002Y133795D03*
X559591D03*
X597044Y130268D03*
X593636D03*
X600522Y130253D03*
X603924D03*
X635500Y346300D03*
X630500D03*
X627000D03*
X639000D03*
X848660Y785690D03*
X1175156Y134519D03*
X1171622Y136228D03*
X1168207Y136226D03*
X1178558Y134518D03*
X1240709Y146753D03*
X1237308D03*
X1269834Y143834D03*
X1266432D03*
X1289500Y274200D03*
G54D21*
X92200Y273940D03*
X95959Y513567D03*
X82017Y490086D03*
Y494086D03*
X84200Y510500D03*
Y502500D03*
X95387Y496084D03*
Y500084D03*
X84200Y506500D03*
X95387Y504084D03*
X84200Y514500D03*
X95820Y541681D03*
X96736Y526266D03*
X95959Y517567D03*
X84200Y518500D03*
X95820Y545681D03*
X70700Y535000D03*
X84200Y538500D03*
Y534500D03*
X70300Y526900D03*
X74200Y522500D03*
X96736Y530266D03*
X74000Y545700D03*
X84200Y554500D03*
X95820Y549681D03*
X84162Y558640D03*
X101900Y275460D03*
X130592Y470680D03*
X135109Y426337D03*
X135108Y430365D03*
X181700Y517500D03*
X214338Y441845D03*
X211238Y425445D03*
X217800Y448200D03*
X204600Y502800D03*
Y506800D03*
Y510900D03*
Y514900D03*
X213200Y542500D03*
Y538500D03*
Y546500D03*
Y550500D03*
X254200Y477500D03*
X243600Y455600D03*
Y473600D03*
X234843Y477829D03*
Y473829D03*
X254200Y481500D03*
X253200Y486000D03*
Y490000D03*
X234843Y485929D03*
Y489929D03*
X234800Y506000D03*
Y502000D03*
X718750Y17920D03*
X870100Y765800D03*
X858640Y790220D03*
X905600Y112500D03*
X900000Y765400D03*
X1007628Y23605D03*
Y27605D03*
X1037681Y2842D03*
X1045263Y2948D03*
X1052112Y18357D03*
X1073200Y36500D03*
X1068700Y24500D03*
X1073200Y32500D03*
X1068700Y20500D03*
X1054900Y36615D03*
X1065425Y48823D03*
Y44323D03*
X1061346Y68390D03*
Y72400D03*
X1077500Y3500D03*
X1077600Y12400D03*
X1077500Y7600D03*
X1378239Y169235D03*
G54D12*
X4100Y865800D03*
X46678Y-681D03*
X50400Y826100D03*
X107400Y119000D03*
X1374900Y761800D03*
X1383700Y138500D03*
X1396600Y862800D03*
G54D22*
X88800Y273940D03*
X92559Y513567D03*
X78617Y490086D03*
Y494086D03*
X80800Y510500D03*
Y502500D03*
X91987Y496084D03*
Y500084D03*
X80800Y506500D03*
X91987Y504084D03*
X80800Y514500D03*
X92420Y541681D03*
X93336Y526266D03*
X92559Y517567D03*
X80800Y518500D03*
X92420Y545681D03*
X67300Y535000D03*
X80800Y538500D03*
Y534500D03*
X66900Y526900D03*
X70800Y522500D03*
X93336Y530266D03*
X70600Y545700D03*
X80800Y554500D03*
X92420Y549681D03*
X80762Y558640D03*
X98500Y275460D03*
X131709Y426337D03*
X131708Y430365D03*
X127192Y470680D03*
X178300Y517500D03*
X210938Y441845D03*
X207838Y425445D03*
X231443Y477829D03*
X214400Y448200D03*
X231443Y473829D03*
X201200Y502800D03*
Y506800D03*
X231443Y485929D03*
Y489929D03*
X231400Y506000D03*
Y502000D03*
X201200Y510900D03*
Y514900D03*
X209800Y542500D03*
Y538500D03*
Y546500D03*
Y550500D03*
X250800Y477500D03*
X240200Y455600D03*
Y473600D03*
X250800Y481500D03*
X249800Y486000D03*
Y490000D03*
X715350Y17920D03*
X866700Y765800D03*
X855240Y790220D03*
X902200Y112500D03*
X896600Y765400D03*
X1004228Y23605D03*
Y27605D03*
X1041863Y2948D03*
X1034281Y2842D03*
X1074100Y3500D03*
X1074200Y12400D03*
X1074100Y7600D03*
X1048712Y18357D03*
X1069800Y36500D03*
X1065300Y24500D03*
X1069800Y32500D03*
X1065300Y20500D03*
X1051500Y36615D03*
X1062025Y48823D03*
Y44323D03*
X1057946Y68390D03*
Y72400D03*
X1374839Y169235D03*
G54D31*
X162200Y512500D03*
Y509000D03*
Y505500D03*
X162219Y521720D03*
X162200Y516000D03*
X181700Y443300D03*
X612263Y253108D03*
X639700Y355600D03*
Y359600D03*
X874348Y764898D03*
X1005412Y35919D03*
G36*
G01X54403Y250202D02*
G02X54353I-25J-12800D01*
G01Y245802D01*
G03X54403I25J-8400D01*
G01Y250202D01*
G37*
G54D40*
X856650Y16200D03*
X864150Y20075D03*
Y12325D03*
G54D50*
G01X127746Y-260199D02*
X95746D01*
G01X127746Y-276199D02*
Y-356199D01*
G01D02*
X1310146D01*
G01X127746Y-311699D02*
X1310146D01*
G01X123746Y-260199D02*
G02I-12000J0D01*
G01X118596D02*
G02I-6850J0D01*
G01X111746Y-276199D02*
Y-244199D01*
G01X127746Y-276199D02*
X1310146D01*
G01X522646D02*
Y-356199D01*
G01X660146Y-276199D02*
Y-356199D01*
G01X775146Y-276199D02*
Y-356199D01*
G01X942646Y-276199D02*
Y-356199D01*
G01X1112646Y-276199D02*
Y-356199D01*
G01X1310146Y-276199D02*
Y-356199D01*
G01X1342146Y-260199D02*
X1310146D01*
G01X1338146D02*
G02I-12000J0D01*
G01X1332996D02*
G02I-6850J0D01*
G01X1326146Y-276199D02*
Y-244199D01*
G54D32*
X165800Y512500D03*
Y509000D03*
Y505500D03*
X165819Y521720D03*
X165800Y516000D03*
X185300Y443300D03*
X615863Y253108D03*
X643300Y355600D03*
Y359600D03*
X877948Y764898D03*
X1009012Y35919D03*
G54D41*
X883500Y36100D03*
X879500Y44900D03*
X887500D03*
G54D14*
X54970Y301816D03*
X54977Y298371D03*
X54800Y307100D03*
X54978Y294934D03*
X44800Y422000D03*
Y426000D03*
X65382Y295207D03*
X140800Y510500D03*
X140572Y505467D03*
X141816Y517120D03*
X142300Y522000D03*
X272800Y759000D03*
X555280Y137538D03*
X555300Y134094D03*
X626300Y354600D03*
X833600Y176200D03*
Y179700D03*
X875100Y52700D03*
X1039817Y14710D03*
X1327800Y250000D03*
G54D23*
X93300Y476400D03*
Y472400D03*
X80642Y463549D03*
X77500Y478600D03*
X93300Y484600D03*
Y480400D03*
X70800Y498500D03*
X70408Y506552D03*
X80800Y546500D03*
Y530500D03*
Y542500D03*
Y522500D03*
Y550500D03*
X80622Y562789D03*
X76700Y729300D03*
Y733300D03*
X114400Y288100D03*
X108400Y731900D03*
Y727900D03*
X139146Y430391D03*
X189500Y403300D03*
X189700Y419800D03*
X210802Y479619D03*
Y475619D03*
X206826Y448165D03*
X222838Y466300D03*
Y462300D03*
X211023Y487704D03*
Y483704D03*
X210050Y495744D03*
Y491744D03*
X209800Y525500D03*
Y521500D03*
Y534500D03*
Y530500D03*
X222800Y550500D03*
Y558500D03*
Y554500D03*
X239800Y478000D03*
X261838Y477600D03*
X249800Y494100D03*
X239800Y490000D03*
Y486000D03*
Y482000D03*
X261838Y481600D03*
X260300Y588500D03*
Y593000D03*
X294300Y578500D03*
Y583000D03*
Y588500D03*
X507000Y788700D03*
X712163Y37236D03*
X715370Y29700D03*
X715390Y25490D03*
X715130Y53200D03*
Y49100D03*
X862860Y788880D03*
X878510Y792910D03*
X952800Y67900D03*
Y72000D03*
X1017146Y57597D03*
X1043500Y36615D03*
G54D51*
G01X145579Y-328699D02*
Y-346199D01*
X154313D01*
G01X167446Y-334533D02*
Y-346199D01*
G01Y-329866D02*
X167009Y-329574D01*
Y-328991D01*
X167446Y-328699D01*
X167883Y-328991D01*
Y-329574D01*
X167446Y-329866D01*
G01X181889Y-350574D02*
X183418Y-351741D01*
X185164Y-352032D01*
X186692Y-351741D01*
X188003Y-350283D01*
X188876Y-348241D01*
Y-334533D01*
G01Y-336866D02*
X188003Y-335699D01*
X186692Y-334824D01*
X185164Y-334533D01*
X183418Y-335116D01*
X182326Y-336282D01*
X181452Y-338324D01*
X181016Y-340366D01*
X181234Y-342116D01*
X182108Y-344158D01*
X183418Y-345616D01*
X185164Y-346199D01*
X186474Y-345907D01*
X188003Y-344741D01*
X188876Y-343575D01*
G01X198734Y-346199D02*
Y-328699D01*
G01Y-337157D02*
X199826Y-335699D01*
X200918Y-334824D01*
X202664Y-334533D01*
X203974Y-334824D01*
X205503Y-335991D01*
X206158Y-337741D01*
Y-346199D01*
G01X219946Y-328699D02*
Y-346199D01*
G01X216889Y-334533D02*
X223003D01*
G01X233734Y-346199D02*
Y-334533D01*
G01Y-337449D02*
X234608Y-335991D01*
X235918Y-334824D01*
X237664Y-334533D01*
X239192Y-334824D01*
X240503Y-335991D01*
X241158Y-338032D01*
Y-346199D01*
G01X254946Y-334533D02*
Y-346199D01*
G01Y-329866D02*
X254509Y-329574D01*
Y-328991D01*
X254946Y-328699D01*
X255383Y-328991D01*
Y-329574D01*
X254946Y-329866D01*
G01X268734Y-346199D02*
Y-334533D01*
G01Y-337449D02*
X269608Y-335991D01*
X270918Y-334824D01*
X272664Y-334533D01*
X274192Y-334824D01*
X275503Y-335991D01*
X276158Y-338032D01*
Y-346199D01*
G01X286889Y-350574D02*
X288418Y-351741D01*
X290164Y-352032D01*
X291692Y-351741D01*
X293003Y-350283D01*
X293876Y-348241D01*
Y-334533D01*
G01Y-336866D02*
X293003Y-335699D01*
X291692Y-334824D01*
X290164Y-334533D01*
X288418Y-335116D01*
X287326Y-336282D01*
X286452Y-338324D01*
X286016Y-340366D01*
X286234Y-342116D01*
X287108Y-344158D01*
X288418Y-345616D01*
X290164Y-346199D01*
X291474Y-345907D01*
X293003Y-344741D01*
X293876Y-343575D01*
G01X320579Y-346199D02*
Y-328699D01*
X325819D01*
X327566Y-329574D01*
X328876Y-331616D01*
X329313Y-333949D01*
X328876Y-336282D01*
X327784Y-338032D01*
X325819Y-338908D01*
X320579D01*
G01X346813Y-346199D02*
X338079D01*
Y-328699D01*
X346813D01*
G01X343319Y-337157D02*
X338079D01*
G01X361692Y-336866D02*
X362566Y-335991D01*
X363221Y-334533D01*
X363658Y-332490D01*
X363221Y-330741D01*
X362348Y-329574D01*
X360819Y-328699D01*
X354924D01*
Y-346199D01*
X362129D01*
X363658Y-345033D01*
X364531Y-343282D01*
X364968Y-341241D01*
X364531Y-339199D01*
X363221Y-337449D01*
X361692Y-336866D01*
X354924D01*
G01X390579Y-346199D02*
Y-328699D01*
X395819D01*
X397566Y-329574D01*
X398876Y-331616D01*
X399313Y-333949D01*
X398876Y-336282D01*
X397784Y-338032D01*
X395819Y-338908D01*
X390579D01*
G01X406769Y-346199D02*
Y-328699D01*
X412446Y-343282D01*
X418123Y-328699D01*
Y-346199D01*
G01X434749Y-330158D02*
X433439Y-329282D01*
X431911Y-328699D01*
X430164D01*
X428199Y-329574D01*
X426671Y-331032D01*
X425579Y-332783D01*
X424706Y-335699D01*
X424487Y-338324D01*
X424924Y-340949D01*
X425579Y-342699D01*
X426889Y-344449D01*
X428418Y-345616D01*
X429946Y-346199D01*
X431474D01*
X433003Y-345616D01*
X434313Y-344741D01*
X435405Y-343575D01*
G01X460579Y-346199D02*
Y-328699D01*
X465819D01*
X467566Y-329574D01*
X468876Y-331616D01*
X469313Y-333949D01*
X468876Y-336282D01*
X467784Y-338032D01*
X465819Y-338908D01*
X460579D01*
G01X476987Y-328699D02*
X482446Y-346199D01*
X487905Y-328699D01*
G01X499946D02*
Y-346199D01*
G01X494924Y-328699D02*
X504968D01*
G01X284269Y-301199D02*
Y-283699D01*
X289946Y-298282D01*
X295623Y-283699D01*
Y-301199D01*
G01X307446D02*
X306136Y-300907D01*
X304826Y-299741D01*
X303952Y-297699D01*
X303516Y-295366D01*
X303952Y-293032D01*
X304826Y-290991D01*
X306136Y-289824D01*
X307446Y-289533D01*
X308756Y-289824D01*
X310066Y-290991D01*
X310939Y-293032D01*
X311158Y-295366D01*
X310939Y-297699D01*
X310066Y-299741D01*
X308756Y-300907D01*
X307446Y-301199D01*
G01X328876Y-283699D02*
Y-301199D01*
G01Y-298575D02*
X328003Y-300033D01*
X326692Y-300907D01*
X325164Y-301199D01*
X323418Y-300616D01*
X322108Y-299158D01*
X321234Y-297408D01*
X321016Y-295366D01*
X321234Y-293324D01*
X322108Y-291574D01*
X323418Y-290116D01*
X325164Y-289533D01*
X326692Y-289824D01*
X327784Y-290408D01*
X328876Y-291574D01*
G01X339171Y-293324D02*
X346158D01*
X345503Y-291282D01*
X344411Y-290116D01*
X342883Y-289533D01*
X341354Y-289824D01*
X340044Y-290699D01*
X339171Y-292741D01*
X338734Y-294491D01*
Y-296241D01*
X339171Y-297991D01*
X340263Y-299741D01*
X341573Y-300907D01*
X343101Y-301199D01*
X344629Y-300616D01*
X346158Y-298866D01*
G01X359946Y-301199D02*
Y-283699D01*
G01X556346Y-346199D02*
Y-328699D01*
X553726Y-332199D01*
G01Y-346199D02*
X558966D01*
G01X569043Y-343575D02*
X570352Y-345033D01*
X571881Y-345907D01*
X573846Y-346199D01*
X575811Y-345616D01*
X577339Y-344449D01*
X578431Y-342408D01*
X578649Y-340074D01*
X578213Y-337741D01*
X577121Y-336282D01*
X575592Y-335116D01*
X574064Y-334824D01*
X572536Y-335116D01*
X570571Y-336282D01*
X571226Y-328699D01*
X577121D01*
G01X591346Y-346199D02*
Y-328699D01*
X588726Y-332199D01*
G01Y-346199D02*
X593966D01*
G01X608846Y-328699D02*
X607099Y-329282D01*
X605789Y-330741D01*
X604916Y-332490D01*
X604261Y-334824D01*
X604043Y-337449D01*
X604261Y-340074D01*
X604916Y-342408D01*
X605789Y-344158D01*
X607099Y-345616D01*
X608846Y-346199D01*
X610592Y-345616D01*
X611903Y-344158D01*
X612776Y-342408D01*
X613431Y-340074D01*
X613649Y-337449D01*
X613431Y-334824D01*
X612776Y-332490D01*
X611903Y-330741D01*
X610592Y-329282D01*
X608846Y-328699D01*
G01X621543Y-343575D02*
X622852Y-345033D01*
X624381Y-345907D01*
X626346Y-346199D01*
X628311Y-345616D01*
X629839Y-344449D01*
X630931Y-342408D01*
X631149Y-340074D01*
X630713Y-337741D01*
X629621Y-336282D01*
X628092Y-335116D01*
X626564Y-334824D01*
X625036Y-335116D01*
X623071Y-336282D01*
X623726Y-328699D01*
X629621D01*
G01X543229Y-301199D02*
Y-283699D01*
X548469D01*
X550216Y-284574D01*
X551526Y-286616D01*
X551963Y-288949D01*
X551526Y-291282D01*
X550434Y-293032D01*
X548469Y-293908D01*
X543229D01*
G01X569899Y-285158D02*
X568589Y-284282D01*
X567061Y-283699D01*
X565314D01*
X563349Y-284574D01*
X561821Y-286032D01*
X560729Y-287783D01*
X559856Y-290699D01*
X559637Y-293324D01*
X560074Y-295949D01*
X560729Y-297699D01*
X562039Y-299449D01*
X563568Y-300616D01*
X565096Y-301199D01*
X566624D01*
X568153Y-300616D01*
X569463Y-299741D01*
X570555Y-298575D01*
G01X584342Y-291866D02*
X585216Y-290991D01*
X585871Y-289533D01*
X586308Y-287490D01*
X585871Y-285741D01*
X584998Y-284574D01*
X583469Y-283699D01*
X577574D01*
Y-301199D01*
X584779D01*
X586308Y-300033D01*
X587181Y-298282D01*
X587618Y-296241D01*
X587181Y-294199D01*
X585871Y-292449D01*
X584342Y-291866D01*
X577574D01*
G01X593546Y-307032D02*
X606646D01*
G01X612574Y-301199D02*
Y-283699D01*
X622618Y-301199D01*
Y-283699D01*
G01X635096Y-301199D02*
X633349Y-300907D01*
X631821Y-299741D01*
X630511Y-297991D01*
X629637Y-295949D01*
X629201Y-293616D01*
Y-291282D01*
X629637Y-288949D01*
X630511Y-286907D01*
X631821Y-285158D01*
X633349Y-283991D01*
X635096Y-283699D01*
X636842Y-283991D01*
X638371Y-285158D01*
X639681Y-286907D01*
X640555Y-288949D01*
X640991Y-291282D01*
Y-293616D01*
X640555Y-295949D01*
X639681Y-297991D01*
X638371Y-299741D01*
X636842Y-300907D01*
X635096Y-301199D01*
G01X685937Y-283699D02*
X691396Y-301199D01*
X696855Y-283699D01*
G01X713263Y-301199D02*
X704529D01*
Y-283699D01*
X713263D01*
G01X709769Y-292157D02*
X704529D01*
G01X722029Y-301199D02*
Y-283699D01*
X727488D01*
X729234Y-284574D01*
X730326Y-285741D01*
X730763Y-288074D01*
X730326Y-290408D01*
X729016Y-291866D01*
X727488Y-292741D01*
X722029D01*
G01X727488D02*
X730763Y-301199D01*
G01X743896Y-301782D02*
X743459Y-301491D01*
Y-300907D01*
X743896Y-300616D01*
X744333Y-300907D01*
Y-301491D01*
X743896Y-301782D01*
G01X717646Y-346199D02*
Y-328699D01*
X715026Y-332199D01*
G01Y-346199D02*
X720266D01*
G01X883350Y-336866D02*
X882476Y-335991D01*
X881821Y-334533D01*
X881384Y-332490D01*
X881821Y-330741D01*
X882694Y-329574D01*
X884223Y-328699D01*
X890118D01*
Y-346199D01*
X882913D01*
X881384Y-345033D01*
X880511Y-343282D01*
X880074Y-341241D01*
X880511Y-339199D01*
X881821Y-337449D01*
X883350Y-336866D01*
X890118D01*
G01X872181Y-343866D02*
X870434Y-345324D01*
X868469Y-346199D01*
X866723D01*
X864976Y-345324D01*
X863666Y-343866D01*
X863011Y-341824D01*
X863448Y-339783D01*
X864539Y-338032D01*
X866504Y-336866D01*
X869124Y-336282D01*
X870653Y-335116D01*
X871308Y-333074D01*
X870871Y-331032D01*
X869779Y-329574D01*
X868251Y-328699D01*
X866723D01*
X865194Y-329282D01*
X863884Y-330741D01*
G01X855773Y-346199D02*
Y-328699D01*
X850096Y-343282D01*
X844419Y-328699D01*
Y-346199D01*
G01X837399D02*
Y-328699D01*
X833033D01*
X831286Y-329574D01*
X829976Y-330741D01*
X828884Y-332490D01*
X828011Y-334533D01*
X827793Y-337449D01*
X828011Y-340366D01*
X828884Y-342408D01*
X829976Y-344158D01*
X831286Y-345324D01*
X833033Y-346199D01*
X837399D01*
G01X819479Y-283699D02*
Y-301199D01*
X828213D01*
G01X845276D02*
Y-289533D01*
G01Y-291574D02*
X844403Y-290408D01*
X843092Y-289824D01*
X841564Y-289533D01*
X840036Y-290116D01*
X838726Y-291282D01*
X837852Y-293032D01*
X837416Y-295366D01*
X837852Y-297699D01*
X838726Y-299449D01*
X840036Y-300616D01*
X841564Y-301199D01*
X843092Y-300907D01*
X844403Y-300033D01*
X845276Y-298866D01*
G01X854261Y-306449D02*
X855571Y-307032D01*
X857318Y-306449D01*
X858409Y-305283D01*
X859283Y-303824D01*
X860592Y-299158D01*
X863431Y-289533D01*
G01X856444D02*
X860592Y-299158D01*
G01X873071Y-293324D02*
X880058D01*
X879403Y-291282D01*
X878311Y-290116D01*
X876783Y-289533D01*
X875254Y-289824D01*
X873944Y-290699D01*
X873071Y-292741D01*
X872634Y-294491D01*
Y-296241D01*
X873071Y-297991D01*
X874163Y-299741D01*
X875473Y-300907D01*
X877001Y-301199D01*
X878529Y-300616D01*
X880058Y-298866D01*
G01X890789Y-301199D02*
Y-289533D01*
G01Y-291866D02*
X891881Y-290699D01*
X892973Y-289824D01*
X894501Y-289533D01*
X895592Y-289824D01*
X896903Y-290699D01*
G01X959846Y-328699D02*
X962902Y-346199D01*
X966396Y-328699D01*
X969889Y-346199D01*
X972946Y-328699D01*
G01X979529Y-346199D02*
Y-328699D01*
X984769D01*
X986516Y-329574D01*
X987826Y-331616D01*
X988263Y-333949D01*
X987826Y-336282D01*
X986734Y-338032D01*
X984769Y-338908D01*
X979529D01*
G01X996811Y-346199D02*
Y-328699D01*
G01X1005981D02*
Y-346199D01*
G01Y-337449D02*
X996811D01*
G01X1016058Y-340366D02*
X1021734D01*
G01X1031593Y-346199D02*
Y-328699D01*
G01X1039889D02*
X1031593Y-339491D01*
G01X1041199Y-346199D02*
X1035304Y-334533D01*
G01X1058263Y-346199D02*
X1049529D01*
Y-328699D01*
X1058263D01*
G01X1054769Y-337157D02*
X1049529D01*
G01X1066374Y-346199D02*
Y-328699D01*
X1076418Y-346199D01*
Y-328699D01*
G01X1083874Y-346199D02*
Y-328699D01*
X1093918Y-346199D01*
Y-328699D01*
G01X961593Y-301199D02*
Y-283699D01*
X965959D01*
X967706Y-284574D01*
X969016Y-285741D01*
X970108Y-287490D01*
X970981Y-289533D01*
X971199Y-292449D01*
X970981Y-295366D01*
X970108Y-297408D01*
X969016Y-299158D01*
X967706Y-300324D01*
X965959Y-301199D01*
X961593D01*
G01X980621Y-293324D02*
X987608D01*
X986953Y-291282D01*
X985861Y-290116D01*
X984333Y-289533D01*
X982804Y-289824D01*
X981494Y-290699D01*
X980621Y-292741D01*
X980184Y-294491D01*
Y-296241D01*
X980621Y-297991D01*
X981713Y-299741D01*
X983023Y-300907D01*
X984551Y-301199D01*
X986079Y-300616D01*
X987608Y-298866D01*
G01X998121Y-299158D02*
X999213Y-300324D01*
X1000741Y-301199D01*
X1002051D01*
X1003361Y-300616D01*
X1004234Y-299741D01*
X1004671Y-298575D01*
X1004453Y-296824D01*
X1003579Y-295949D01*
X999649Y-294199D01*
X998776Y-292157D01*
X999213Y-290699D01*
X1000086Y-289824D01*
X1001396Y-289533D01*
X1002706Y-289824D01*
X1004016Y-290699D01*
G01X1018896Y-289533D02*
Y-301199D01*
G01Y-284866D02*
X1018459Y-284574D01*
Y-283991D01*
X1018896Y-283699D01*
X1019333Y-283991D01*
Y-284574D01*
X1018896Y-284866D01*
G01X1033339Y-305574D02*
X1034868Y-306741D01*
X1036614Y-307032D01*
X1038142Y-306741D01*
X1039453Y-305283D01*
X1040326Y-303241D01*
Y-289533D01*
G01Y-291866D02*
X1039453Y-290699D01*
X1038142Y-289824D01*
X1036614Y-289533D01*
X1034868Y-290116D01*
X1033776Y-291282D01*
X1032902Y-293324D01*
X1032466Y-295366D01*
X1032684Y-297116D01*
X1033558Y-299158D01*
X1034868Y-300616D01*
X1036614Y-301199D01*
X1037924Y-300907D01*
X1039453Y-299741D01*
X1040326Y-298575D01*
G01X1050184Y-301199D02*
Y-289533D01*
G01Y-292449D02*
X1051058Y-290991D01*
X1052368Y-289824D01*
X1054114Y-289533D01*
X1055642Y-289824D01*
X1056953Y-290991D01*
X1057608Y-293032D01*
Y-301199D01*
G01X1068121Y-293324D02*
X1075108D01*
X1074453Y-291282D01*
X1073361Y-290116D01*
X1071833Y-289533D01*
X1070304Y-289824D01*
X1068994Y-290699D01*
X1068121Y-292741D01*
X1067684Y-294491D01*
Y-296241D01*
X1068121Y-297991D01*
X1069213Y-299741D01*
X1070523Y-300907D01*
X1072051Y-301199D01*
X1073579Y-300616D01*
X1075108Y-298866D01*
G01X1085839Y-301199D02*
Y-289533D01*
G01Y-291866D02*
X1086931Y-290699D01*
X1088023Y-289824D01*
X1089551Y-289533D01*
X1090642Y-289824D01*
X1091953Y-290699D01*
G01X1132596Y-346199D02*
Y-328699D01*
X1129976Y-332199D01*
G01Y-346199D02*
X1135216D01*
G01X1150096D02*
Y-328699D01*
X1147476Y-332199D01*
G01Y-346199D02*
X1152716D01*
G01X1163666Y-346782D02*
X1171526Y-328699D01*
G01X1185096Y-346199D02*
Y-328699D01*
X1182476Y-332199D01*
G01Y-346199D02*
X1187716D01*
G01X1198448Y-338908D02*
X1199976Y-336866D01*
X1201286Y-335699D01*
X1203033Y-335116D01*
X1204561Y-335699D01*
X1205653Y-336866D01*
X1206526Y-338616D01*
X1206744Y-340657D01*
X1206526Y-342408D01*
X1205653Y-344158D01*
X1204342Y-345616D01*
X1202814Y-346199D01*
X1201068Y-345616D01*
X1199539Y-343866D01*
X1198666Y-341241D01*
X1198448Y-338324D01*
X1198884Y-334533D01*
X1199539Y-332490D01*
X1200631Y-330449D01*
X1202159Y-328991D01*
X1203688Y-328699D01*
X1205216Y-329282D01*
X1206308Y-330741D01*
G01X1216166Y-346782D02*
X1224026Y-328699D01*
G01X1233448Y-331616D02*
X1234758Y-329866D01*
X1236286Y-328991D01*
X1238033Y-328699D01*
X1240216Y-329282D01*
X1241744Y-330741D01*
X1242181Y-332490D01*
X1241963Y-334241D01*
X1241089Y-335699D01*
X1236723Y-338616D01*
X1234758Y-340657D01*
X1233448Y-343575D01*
X1233011Y-346199D01*
X1242181D01*
G01X1255096Y-328699D02*
X1253349Y-329282D01*
X1252039Y-330741D01*
X1251166Y-332490D01*
X1250511Y-334824D01*
X1250293Y-337449D01*
X1250511Y-340074D01*
X1251166Y-342408D01*
X1252039Y-344158D01*
X1253349Y-345616D01*
X1255096Y-346199D01*
X1256842Y-345616D01*
X1258153Y-344158D01*
X1259026Y-342408D01*
X1259681Y-340074D01*
X1259899Y-337449D01*
X1259681Y-334824D01*
X1259026Y-332490D01*
X1258153Y-330741D01*
X1256842Y-329282D01*
X1255096Y-328699D01*
G01X1272596Y-346199D02*
Y-328699D01*
X1269976Y-332199D01*
G01Y-346199D02*
X1275216D01*
G01X1285948Y-338908D02*
X1287476Y-336866D01*
X1288786Y-335699D01*
X1290533Y-335116D01*
X1292061Y-335699D01*
X1293153Y-336866D01*
X1294026Y-338616D01*
X1294244Y-340657D01*
X1294026Y-342408D01*
X1293153Y-344158D01*
X1291842Y-345616D01*
X1290314Y-346199D01*
X1288568Y-345616D01*
X1287039Y-343866D01*
X1286166Y-341241D01*
X1285948Y-338324D01*
X1286384Y-334533D01*
X1287039Y-332490D01*
X1288131Y-330449D01*
X1289659Y-328991D01*
X1291188Y-328699D01*
X1292716Y-329282D01*
X1293808Y-330741D01*
G01X1180293Y-301199D02*
Y-283699D01*
X1184659D01*
X1186406Y-284574D01*
X1187716Y-285741D01*
X1188808Y-287490D01*
X1189681Y-289533D01*
X1189899Y-292449D01*
X1189681Y-295366D01*
X1188808Y-297408D01*
X1187716Y-299158D01*
X1186406Y-300324D01*
X1184659Y-301199D01*
X1180293D01*
G01X1206526D02*
Y-289533D01*
G01Y-291574D02*
X1205653Y-290408D01*
X1204342Y-289824D01*
X1202814Y-289533D01*
X1201286Y-290116D01*
X1199976Y-291282D01*
X1199102Y-293032D01*
X1198666Y-295366D01*
X1199102Y-297699D01*
X1199976Y-299449D01*
X1201286Y-300616D01*
X1202814Y-301199D01*
X1204342Y-300907D01*
X1205653Y-300033D01*
X1206526Y-298866D01*
G01X1220096Y-283699D02*
Y-301199D01*
G01X1217039Y-289533D02*
X1223153D01*
G01X1234321Y-293324D02*
X1241308D01*
X1240653Y-291282D01*
X1239561Y-290116D01*
X1238033Y-289533D01*
X1236504Y-289824D01*
X1235194Y-290699D01*
X1234321Y-292741D01*
X1233884Y-294491D01*
Y-296241D01*
X1234321Y-297991D01*
X1235413Y-299741D01*
X1236723Y-300907D01*
X1238251Y-301199D01*
X1239779Y-300616D01*
X1241308Y-298866D01*
G01X1425733Y-51181D02*
X-29385D01*
G01X-33322Y-47244D02*
G03X-29385Y-51181I3937J0D01*
G01X-33322Y-47244D02*
Y893701D01*
G01X-7874Y102402D02*
Y212205D01*
G01Y102402D02*
G03X0Y94528I7874J0D01*
G01Y212205D02*
G03X-7874I-3937J0D01*
G01Y237402D02*
G03X0I3937J-1D01*
G01X-7874D02*
Y406693D01*
G01X0D02*
G03X-7874I-3937J0D01*
G01Y431890D02*
G03X0I3937J0D01*
G01X-7874D02*
Y601181D01*
G01X0D02*
G03X-7874I-3937J0D01*
G01Y626378D02*
Y795669D01*
G01Y626378D02*
G03X0I3937J0D01*
G01Y795669D02*
G03X-7874I-3937J0D01*
G01Y820866D02*
G03X0I3937J0D01*
G01X-7874Y844488D02*
Y820866D01*
G01X-3937Y848425D02*
G03X-7874Y844488I0J-3937D01*
G01X93307Y848425D02*
X-3937D01*
G01X-29385Y897638D02*
G03X-33322Y893701I0J-3937D01*
G01X-29385Y897638D02*
X93307D01*
G01X98425Y94528D02*
X0D01*
G01X1400000Y36220D02*
G03X1398031Y38189I-1969J0D01*
G01X1396654D01*
G02X1394685Y40157I0J1969D01*
G01Y71654D01*
G02X1396654Y73622I1969J-1D01*
G01X1398031D01*
G03X1400000Y75591I0J1969D01*
G01Y836614D01*
G03X1396063Y840551I-3937J0D01*
G01X1368504D01*
G02X1363386Y845669I0J5118D01*
G01Y871654D01*
G03X1361417Y873622I-1969J-1D01*
G01X1358268D01*
G02X1356299Y875591I0J1969D01*
G01Y892521D01*
X1352363Y897638D01*
X1218110D01*
X1214173Y892520D01*
Y875984D01*
G02X1205512I-4331J0D01*
G01Y892520D01*
X1201575Y897638D01*
X1029528D01*
X1025591Y892520D01*
Y875591D01*
G02X1023622Y873622I-1969J0D01*
G01X1020472D01*
G03X1018504Y871654I0J-1968D01*
G01Y845669D01*
G02X1013386Y840551I-5118J0D01*
G01X1008433D01*
G03X988748Y820866I0J-19685D01*
G01Y650669D01*
G02X983748Y645669I-5000J0D01*
G01X926819D01*
G02X921819Y650669I0J5000D01*
G01Y820866D01*
G03X902134Y840551I-19685J0D01*
G01X872441D01*
G02X867323Y845669I0J5118D01*
G01Y871654D01*
G03X865354Y873622I-1969J-1D01*
G01X862205D01*
G02X860236Y875591I0J1969D01*
G01Y892521D01*
X856300Y897638D01*
X722048D01*
X718110Y892519D01*
Y875984D01*
G02X709449I-4331J0D01*
G01Y892520D01*
X705512Y897638D01*
X533465D01*
X529528Y892520D01*
Y875591D01*
G02X527559Y873622I-1969J0D01*
G01X524409D01*
G03X522441Y871654I0J-1968D01*
G01Y845669D01*
G02X517323Y840551I-5118J0D01*
G01X455118D01*
G02X450000Y845669I0J5118D01*
G01Y871654D01*
G03X448031Y873622I-1968J0D01*
G01X444882D01*
G02X442913Y875591I0J1969D01*
G01Y892521D01*
X438977Y897638D01*
X304725D01*
X300787Y892519D01*
Y875984D01*
G02X292126I-4331J0D01*
G01Y892521D01*
X288190Y897638D01*
X116142D01*
X112205Y892520D01*
Y875591D01*
G02X110236Y873622I-1969J0D01*
G01X107087D01*
G03X105118Y871654I0J-1969D01*
G01Y845669D01*
G02X100000Y840551I-5118J0D01*
G01X3937D01*
G03X0Y836614I0J-3937D01*
G01Y110276D01*
G03X7874Y102402I7874J0D01*
G01X196654D01*
G02X204528Y94528I0J-7874D01*
G01Y7874D01*
G03X212402Y0I7874J0D01*
G01X471014D01*
G02X478888Y-7874I0J-7874D01*
G01Y-11811D01*
G03X486762Y-19685I7874J0D01*
G01X1302165D01*
G03X1306102Y-15748I0J3937D01*
G01Y-3937D01*
G02X1310039Y0I3937J0D01*
G01X1396063D01*
G03X1400000Y3937I0J3937D01*
G01Y36220D01*
G01X93307Y848425D02*
G03X97244Y852362I0J3937D01*
G01Y893701D02*
Y852362D01*
G01Y893701D02*
G03X93307Y897638I-3937J0D01*
G01X192717Y94528D02*
X123622D01*
G01Y102402D02*
G03Y94528I0J-3937D01*
G01X98425D02*
G03Y102402I0J3937D01*
G01X196654Y0D02*
G03X204528Y-7874I7874J0D01*
G01X196654Y0D02*
Y29961D01*
G01X204528D02*
G03X196654I-3937J0D01*
G01Y55157D02*
Y90591D01*
G01Y55157D02*
G03X204528I3937J0D01*
G01X196654Y90591D02*
G03X192717Y94528I-3937J0D01*
G01X232077Y-7874D02*
G03Y0I0J3937D01*
G01Y-7874D02*
X204528D01*
G01X434439D02*
X257274D01*
G01Y0D02*
G03Y-7874I0J-3937D01*
G01X365945Y38188D02*
G03X367914Y40156I0J1969D01*
G01X354134D02*
G03X356103Y38188I1969J1D01*
G01D02*
X365945D01*
G01X354134Y71653D02*
Y40156D01*
G01X367914Y71653D02*
G03X365945Y73621I-1969J-1D01*
G01X356103D02*
G03X354134Y71653I0J-1969D01*
G01X365945Y73621D02*
X356103D01*
G01X367914Y40156D02*
Y71653D01*
G01X434439Y-7874D02*
G03Y0I0J3937D01*
G01X471014Y-15748D02*
G03X463140Y-7874I-7874J0D01*
G01D02*
X459636D01*
G01Y0D02*
G03Y-7874I0J-3937D01*
G01X707234Y-27559D02*
X478888D01*
G01X471014Y-19685D02*
G03X478888Y-27559I7874J0D01*
G01X471014Y-19685D02*
Y-15748D01*
G01X870226Y-27559D02*
X732431D01*
G01Y-19685D02*
G03Y-27559I0J-3937D01*
G01X707234D02*
G03Y-19685I0J3937D01*
G01X870226Y-27559D02*
G03Y-19685I1J3937D01*
G01X1072589Y-27559D02*
X895423D01*
G01Y-19685D02*
G03Y-27559I0J-3937D01*
G01X1072589D02*
G03Y-19685I0J3937D01*
G01X1097785D02*
G03Y-27559I1J-3937D01*
G01X1336086Y-8662D02*
X1318701D01*
G03X1314764Y-12599I0J-3937D01*
G01Y-23622D01*
G02X1310827Y-27559I-3937J0D01*
G01X1097785D01*
G01X1336086Y-8662D02*
G03Y-1I0J4330D01*
G01X1361283D02*
G03Y-8662I0J-4330D01*
G01X1407874Y13026D02*
Y-4725D01*
G02X1403937Y-8662I-3937J0D01*
G01X1361283D01*
G01X1403937Y848425D02*
X1375197D01*
G01X1371260Y852362D02*
G03X1375197Y848425I3937J0D01*
G01X1371260Y852362D02*
Y893701D01*
G01X1375197Y897638D02*
G03X1371260Y893701I0J-3937D01*
G01X1375197Y897638D02*
X1425733D01*
G01X1407874Y30709D02*
Y219685D01*
G01X1400000Y30709D02*
G03X1407874I3937J0D01*
G01Y13026D02*
G03X1400000I-3937J-1D01*
G01X1407874Y219685D02*
G03X1400000I-3937J0D01*
G01Y244882D02*
G03X1407874I3937J0D01*
G01Y414173D02*
Y244882D01*
G01Y608661D02*
Y439370D01*
G01X1400000D02*
G03X1407874I3937J0D01*
G01Y414173D02*
G03X1400000I-3937J0D01*
G01X1407874Y608661D02*
G03X1400000I-3937J0D01*
G01Y626378D02*
G03X1407874I3937J0D01*
G01Y795669D02*
Y626378D01*
G01Y795669D02*
G03X1400000I-3937J0D01*
G01Y820866D02*
G03X1407874I3937J0D01*
G01Y844488D02*
Y820866D01*
G01Y844488D02*
G03X1403937Y848425I-3937J0D01*
G01X1429670Y893701D02*
Y-47244D01*
G01X1425733Y-51181D02*
G03X1429670Y-47244I0J3937D01*
G01Y893701D02*
G03X1425733Y897638I-3937J0D01*
G54D42*
X897500Y141714D03*
X895300D03*
X897500Y137800D03*
X895300D03*
X897500Y133877D03*
X895300D03*
X897500Y129903D03*
X895300D03*
X897500Y153562D03*
X895300D03*
X897500Y149600D03*
X895300D03*
X897500Y145688D03*
X895300D03*
X897500Y161436D03*
X895300D03*
X897500Y157499D03*
X895300D03*
X893100Y236200D03*
X890900D03*
X936300Y129900D03*
X934100D03*
X911900Y137800D03*
X909700D03*
X925850Y149620D03*
X923650D03*
X926700Y165338D03*
X924500D03*
X912900Y181100D03*
X910700D03*
X926700Y185168D03*
X924500D03*
X926700Y204700D03*
X924500D03*
X934800D03*
X932600D03*
X940500D03*
X939500Y224400D03*
Y232300D03*
X936600Y236210D03*
X934400D03*
X928600D03*
X926400D03*
X936600Y228327D03*
X934400D03*
X936600Y220480D03*
X934400D03*
X928600D03*
X926400D03*
X912900Y216500D03*
X910700D03*
X928600Y228327D03*
X926400D03*
X926700Y212600D03*
X924500D03*
X934800D03*
X932600D03*
X955200Y137800D03*
X953000D03*
X951000Y149600D03*
X948800D03*
X954368Y161468D03*
X952168D03*
X954368Y157468D03*
X952168D03*
X966200Y165338D03*
X964000D03*
X974000D03*
X971800D03*
X958300Y173218D03*
X956100D03*
X966200D03*
X964000D03*
X974000D03*
X971800D03*
X958300Y165338D03*
X956100D03*
X950300D03*
X948100D03*
X950300Y173218D03*
X948100D03*
X973900Y177150D03*
X966200Y185168D03*
X964000D03*
X974000D03*
X971800D03*
X958300Y192900D03*
X956100D03*
X966200D03*
X964000D03*
X974000D03*
X971800D03*
X942700Y204700D03*
X973850Y216510D03*
X941700Y224400D03*
Y232300D03*
X960100Y224400D03*
X957900D03*
X952300D03*
X950100D03*
X968000D03*
X965800D03*
X952300Y232300D03*
X950100D03*
X960100D03*
X957900D03*
X968000D03*
X965800D03*
X995600Y161400D03*
X993400D03*
X995600Y169268D03*
X993400D03*
X995600Y173268D03*
X993400D03*
X995500Y157500D03*
X993300D03*
X991600Y165400D03*
X989400D03*
X995600Y177168D03*
X993400D03*
X995600Y181068D03*
X993400D03*
X990600Y185500D03*
X988400D03*
X995600Y188968D03*
X993400D03*
X995600Y192868D03*
X993400D03*
X995600Y196868D03*
X993400D03*
X976100Y177150D03*
X995600Y208668D03*
X993400D03*
X995600Y200768D03*
X993400D03*
X995600Y204668D03*
X993400D03*
X995600Y224368D03*
X993400D03*
X976050Y216510D03*
X995600Y228368D03*
X993400D03*
X995600Y212568D03*
X993400D03*
X995600Y216518D03*
X993400D03*
X995600Y220468D03*
X993400D03*
X995600Y236200D03*
X993400D03*
X995600Y232268D03*
X993400D03*
G54D33*
X195000Y409040D03*
Y411600D03*
X187600Y409040D03*
Y411600D03*
X195000Y414160D03*
X187600D03*
X207938Y436405D03*
Y433845D03*
Y431285D03*
X215338Y436405D03*
Y433845D03*
Y431285D03*
G54D15*
X51370Y301816D03*
X51377Y298371D03*
X51200Y307100D03*
X61782Y295207D03*
X51378Y294934D03*
X41200Y422000D03*
Y426000D03*
X137200Y510500D03*
X136972Y505467D03*
X138216Y517120D03*
X138700Y522000D03*
X269200Y759000D03*
X551680Y137538D03*
X551700Y134094D03*
X622700Y354600D03*
X830000Y176200D03*
Y179700D03*
X871500Y52700D03*
X1036217Y14710D03*
X1324200Y250000D03*
G54D24*
X96700Y476400D03*
Y472400D03*
X84042Y463549D03*
X80900Y478600D03*
X96700Y484600D03*
Y480400D03*
X74200Y498500D03*
X73808Y506552D03*
X84200Y546500D03*
Y530500D03*
Y542500D03*
Y522500D03*
Y550500D03*
X84022Y562789D03*
X80100Y729300D03*
Y733300D03*
X117800Y288100D03*
X111800Y731900D03*
Y727900D03*
X142546Y430391D03*
X192900Y403300D03*
X193100Y419800D03*
X214202Y479619D03*
Y475619D03*
X210226Y448165D03*
X226238Y466300D03*
Y462300D03*
X214423Y487704D03*
Y483704D03*
X213450Y495744D03*
Y491744D03*
X213200Y525500D03*
Y521500D03*
Y534500D03*
Y530500D03*
X226200Y550500D03*
Y558500D03*
Y554500D03*
X243200Y478000D03*
X265238Y477600D03*
X253200Y494100D03*
X243200Y490000D03*
Y486000D03*
Y482000D03*
X265238Y481600D03*
X263700Y588500D03*
Y593000D03*
X297700Y578500D03*
Y583000D03*
Y588500D03*
X510400Y788700D03*
X715563Y37236D03*
X718770Y29700D03*
X718790Y25490D03*
X718530Y53200D03*
Y49100D03*
X866260Y788880D03*
X881910Y792910D03*
X956200Y67900D03*
Y72000D03*
X1020546Y57597D03*
X1046900Y36615D03*
G54D16*
X50800Y334700D03*
Y342300D03*
X85400Y268400D03*
Y260800D03*
X87561Y317727D03*
Y325327D03*
X228500Y142700D03*
Y150300D03*
X582363Y237408D03*
Y229808D03*
X669163Y243108D03*
Y250708D03*
X693163Y243108D03*
X677163D03*
X685163D03*
X704700Y278200D03*
X693163Y250708D03*
X677163D03*
X685163D03*
X704700Y285800D03*
X708600Y238700D03*
X716600D03*
X724600D03*
X732600D03*
X708600Y246300D03*
X716600D03*
X724600D03*
X732600D03*
X719900Y278200D03*
X712300D03*
X735100D03*
X727500D03*
X719900Y285800D03*
X712300D03*
X735100D03*
X727500D03*
X1242000Y221800D03*
Y214200D03*
X1234000Y221800D03*
Y214200D03*
X1236500Y266200D03*
Y273800D03*
X1228500Y266200D03*
Y273800D03*
X1244500Y266200D03*
Y273800D03*
X1250000Y221800D03*
Y214200D03*
X1258500Y221800D03*
Y214200D03*
X1252500Y266200D03*
Y273800D03*
X1260500Y266200D03*
Y273800D03*
X1363500Y260200D03*
Y267800D03*
G54D34*
X240840Y460900D03*
X243400D03*
X245960D03*
X240840Y468300D03*
X243400D03*
X245960D03*
G54D25*
X72900Y733100D03*
X148500Y525300D03*
X158500Y526300D03*
X221000Y521800D03*
X294500Y149300D03*
X290178Y736231D03*
X273500Y736200D03*
X322178Y736231D03*
X306178D03*
X503178Y788231D03*
X487000Y788200D03*
X488500Y811800D03*
X535178Y788231D03*
X519069Y788767D03*
X556531Y364880D03*
X560531D03*
X635500Y366900D03*
X645663Y238308D03*
X639000Y366900D03*
X847500Y765700D03*
X862678Y765731D03*
X892678Y765231D03*
X1204335Y138491D03*
X1207745Y138490D03*
X1266432Y154937D03*
X1269834D03*
X1307400Y693700D03*
X1306000Y716800D03*
X1324900Y693700D03*
X1341400D03*
G54D43*
X900668Y161468D03*
X902868D03*
X905000Y165300D03*
X907200D03*
X899000Y169268D03*
X901200D03*
X899000Y173218D03*
X901200D03*
X899000Y196818D03*
X901200D03*
X899000Y208668D03*
X901200D03*
X899000Y200768D03*
X901200D03*
X899000Y204718D03*
X901200D03*
X899000Y192918D03*
X901200D03*
X899000Y188968D03*
X901200D03*
X904100Y185200D03*
X906300D03*
X899000Y181068D03*
X901200D03*
X899000Y177168D03*
X901200D03*
X899000Y236200D03*
X901200D03*
X899000Y212568D03*
X901200D03*
X899000Y216518D03*
X901200D03*
X899000Y220468D03*
X901200D03*
X899000Y224368D03*
X901200D03*
X899000Y228318D03*
X901200D03*
X899000Y232268D03*
X901200D03*
X938200Y141700D03*
X940400D03*
X930250Y157500D03*
X932450D03*
X938350D03*
X940550D03*
X932600Y165338D03*
X934800D03*
X940500D03*
X924500Y173218D03*
X926700D03*
X932600D03*
X934800D03*
X940500D03*
X932600Y185168D03*
X934800D03*
X940500D03*
X924500Y192900D03*
X926700D03*
X940500D03*
X932600D03*
X934800D03*
X918300Y216550D03*
X920500D03*
X934400Y232300D03*
X936600D03*
X926400D03*
X928600D03*
X934400Y224400D03*
X936600D03*
X926400D03*
X928600D03*
X940500Y212600D03*
X957400Y126000D03*
X959600D03*
X964050Y161400D03*
X966250D03*
X970900Y149600D03*
X973100D03*
X942700Y165338D03*
Y173218D03*
X956100Y185168D03*
X958300D03*
X948100Y204700D03*
X950300D03*
X948100Y185168D03*
X950300D03*
X956100Y204700D03*
X958300D03*
X964000D03*
X966200D03*
X971800D03*
X974000D03*
X942700Y185168D03*
Y192900D03*
X948100D03*
X950300D03*
X950100Y236210D03*
X952300D03*
X965700Y220500D03*
X967900D03*
X957900Y228327D03*
X960100D03*
X957800Y220500D03*
X960000D03*
X957900Y236210D03*
X960100D03*
X965800Y236200D03*
X968000D03*
X950100Y220500D03*
X952300D03*
X965800Y228300D03*
X968000D03*
X950100Y228327D03*
X952300D03*
X948100Y212600D03*
X950300D03*
X956100D03*
X958300D03*
X964000D03*
X966200D03*
X971600Y212624D03*
X973800D03*
X942700Y212600D03*
X997300Y137768D03*
X999500D03*
X997300Y129900D03*
X999500D03*
X997300Y141768D03*
X999500D03*
X982500Y137800D03*
X984700D03*
X997300Y145668D03*
X999500D03*
X997300Y149618D03*
X999500D03*
X997300Y153600D03*
X999500D03*
X999168Y161468D03*
X1001368D03*
X981500Y177150D03*
X983700D03*
X981350Y185050D03*
X983550D03*
X1001100Y236200D03*
X1003300D03*
X981400Y216505D03*
X983600D03*
G54D35*
X280300Y148900D03*
X301700Y780100D03*
X573634Y243270D03*
X621263Y233108D03*
X695200Y817300D03*
X716287Y201942D03*
X1162807Y823010D03*
X1306700Y271400D03*
X1323900Y817400D03*
G54D26*
X72900Y729500D03*
X148500Y521700D03*
X158500Y522700D03*
X221000Y518200D03*
X294500Y145700D03*
X290178Y732631D03*
X273500Y732600D03*
X322178Y732631D03*
X306178D03*
X503178Y784631D03*
X487000Y784600D03*
X488500Y808200D03*
X535178Y784631D03*
X519069Y785167D03*
X556531Y361280D03*
X560531D03*
X635500Y363300D03*
X645663Y234708D03*
X639000Y363300D03*
X847500Y762100D03*
X862678Y762131D03*
X892678Y761631D03*
X1204335Y134891D03*
X1207745Y134890D03*
X1266432Y151337D03*
X1269834D03*
X1307400Y690100D03*
X1306000Y713200D03*
X1324900Y690100D03*
X1341400D03*
G54D17*
X57700Y499200D03*
X53600D03*
X92360Y566710D03*
X110000Y291200D03*
X145000Y461700D03*
X141000D03*
X150150Y452690D03*
X155680Y452630D03*
X146150Y452690D03*
X137000Y461200D03*
X140500Y452690D03*
X164000Y461200D03*
X161500Y501700D03*
X164000Y795200D03*
X160000D03*
X182300Y411300D03*
X193650Y458522D03*
X189650D03*
X197500Y574200D03*
X191500Y584700D03*
X199500Y716200D03*
X171300Y739500D03*
X167300D03*
X199500Y771700D03*
X200500Y411700D03*
X230571Y469717D03*
X221000Y538200D03*
X229000Y521700D03*
X225000Y529200D03*
X229000D03*
X201500Y574200D03*
X203500Y716200D03*
Y771700D03*
X237500Y135700D03*
X245500D03*
X241500D03*
X235100Y466200D03*
X251800Y466400D03*
X274406Y723098D03*
X278406D03*
X286906Y772098D03*
X299164Y772291D03*
X295079Y772050D03*
X303406Y772098D03*
X323406Y771098D03*
X319406D03*
X476200Y380400D03*
X480200D03*
X487906Y775098D03*
X491906D03*
X500406Y824098D03*
X512679Y824050D03*
X508579D03*
X516906Y824098D03*
X524906D03*
X528906D03*
X711510Y13880D03*
X715380Y25480D03*
X715130Y49100D03*
X837000Y778200D03*
X852400Y87500D03*
X871000Y82200D03*
X848100Y87600D03*
X856906Y752098D03*
X860906D03*
X869906Y801098D03*
X893100Y38100D03*
X875000Y93200D03*
X879500D03*
X884000D03*
X888500D03*
X893000D03*
X897500D03*
X902000D03*
X906500D03*
X882049Y803660D03*
X877949D03*
X886276Y803708D03*
X894406Y801098D03*
X898406D03*
X911000Y93200D03*
X915500D03*
X920000D03*
X933500D03*
X929000D03*
X924500D03*
X938000D03*
X956000D03*
X990552Y104500D03*
X986552D03*
X1003100D03*
X999000D03*
X987039Y157215D03*
X1040140Y10963D03*
X1035830Y10919D03*
X1044147Y13790D03*
X1049161Y11807D03*
X1073250Y32450D03*
X1046950Y36565D03*
X1051450D03*
X1068750Y20450D03*
X1065475Y52273D03*
X1061342Y75796D03*
X1293500Y277700D03*
X1302128Y680567D03*
X1306128D03*
X1314628Y729567D03*
X1325500Y729700D03*
X1334128Y729567D03*
X1338128D03*
X1355000Y283200D03*
X1359000D03*
X1351000D03*
G54D44*
X907900Y127000D03*
Y124800D03*
X915793Y127000D03*
Y124800D03*
X923600Y127000D03*
Y124800D03*
X931532Y127000D03*
Y124800D03*
X915768Y180068D03*
Y177868D03*
X915730Y237800D03*
Y235600D03*
X919700Y237800D03*
Y235600D03*
X907893Y237800D03*
Y235600D03*
X911800Y237800D03*
Y235600D03*
X923604Y237900D03*
Y235700D03*
X966900Y127100D03*
Y124900D03*
X974768Y127100D03*
Y124900D03*
X970845Y237600D03*
Y235400D03*
X974800Y237600D03*
Y235400D03*
X982728Y127100D03*
Y124900D03*
X978760Y237600D03*
Y235400D03*
X982697Y237600D03*
Y235400D03*
X986600Y237600D03*
Y235400D03*
G54D27*
X105500Y287800D03*
X103500Y457800D03*
X113000Y458800D03*
X197800Y443800D03*
X189600Y443700D03*
X193600D03*
X185500Y457800D03*
X197700Y454635D03*
X177500Y457800D03*
X184500Y545300D03*
X232600Y98600D03*
X210086Y201400D03*
X206076D03*
X202638Y434145D03*
X220838Y431945D03*
X201800Y443800D03*
X230572Y458913D03*
X201700Y454635D03*
X210300Y454100D03*
X214300D03*
X225000Y534800D03*
Y518300D03*
X249995Y98758D03*
X236800Y98500D03*
X251000Y498200D03*
X263000Y752300D03*
X290500Y145800D03*
X285000Y748800D03*
X267500D03*
X295678Y732731D03*
X278050Y733317D03*
X298554Y719713D03*
X286406Y719698D03*
X282406D03*
X290500Y719800D03*
X294506Y719698D03*
X293678Y756731D03*
X289678D03*
X279500Y756300D03*
X282378Y768731D03*
X301000Y744300D03*
X317000Y744800D03*
X311678Y732731D03*
X327678D03*
X310406Y719698D03*
X302554Y719713D03*
X311178Y756731D03*
X307178D03*
X325678D03*
X321678D03*
X495906Y771698D03*
X499906D03*
X498000Y800800D03*
X480800D03*
X502678Y808731D03*
X492500Y808300D03*
X482000D03*
X491900Y784700D03*
X495878Y820731D03*
X521820Y130370D03*
X513820D03*
X525820D03*
X517820D03*
X527000Y771500D03*
X521900Y771400D03*
X517800Y771500D03*
X513700D03*
X509600D03*
X514000Y795800D03*
X530000D03*
X506678Y808731D03*
X520178D03*
X524678Y784731D03*
X534678Y808731D03*
X524178D03*
X570345Y130330D03*
X538678Y808731D03*
X540678Y784731D03*
X542800Y809100D03*
X578467Y130330D03*
X582467D03*
X574345D03*
X584363Y220908D03*
X592363D03*
X588363D03*
X620048Y130544D03*
X612026Y130552D03*
X624048Y130544D03*
X616026Y130552D03*
X659500Y130300D03*
X650500D03*
X655000D03*
X646000D03*
X641963Y234908D03*
X720100Y38100D03*
X715390Y29680D03*
X715130Y53200D03*
X834252Y14300D03*
X820212Y14219D03*
X830252Y14300D03*
X826138Y13604D03*
X838252Y14300D03*
X846252D03*
X873100Y27300D03*
X842252Y14300D03*
X864906Y748698D03*
X868906D03*
X857500Y778300D03*
X841000Y774800D03*
X852400Y762200D03*
X870400Y785700D03*
X844810Y785890D03*
X865378Y797731D03*
X877300Y27300D03*
X906500Y78800D03*
X902000D03*
X897500D03*
X893000D03*
X888500D03*
X875000D03*
X884000D03*
X879500D03*
X893406Y748698D03*
X889306D03*
X885306D03*
X881306D03*
X877200Y748600D03*
X887500Y781300D03*
X882203Y762295D03*
X878600Y785300D03*
X896178Y785731D03*
X892178D03*
X911000Y78800D03*
X915500D03*
X920000D03*
X933500D03*
X929000D03*
X924500D03*
X938000D03*
X951500D03*
Y89800D03*
X947000Y78800D03*
Y89800D03*
X942500Y78800D03*
Y89800D03*
X956000Y78800D03*
X994700Y101100D03*
X1069700Y4600D03*
X1044161Y17868D03*
X1068750Y24550D03*
X1073250Y36550D03*
X1065475Y40873D03*
X1061342Y64994D03*
X1310128Y677167D03*
X1302000Y703300D03*
X1298000Y707300D03*
X1312900Y690200D03*
X1310900Y713700D03*
X1310100Y726200D03*
X1338128Y677167D03*
X1330128D03*
X1326128D03*
X1322128D03*
X1314128D03*
X1319500Y705800D03*
X1336000Y701800D03*
X1329900Y714200D03*
X1325900D03*
X1330400Y690200D03*
X1344900Y714200D03*
X1340900D03*
X1346900Y690200D03*
G54D45*
X927600Y142700D03*
Y144900D03*
X939400Y144500D03*
Y146700D03*
X931500Y144600D03*
Y146800D03*
X951200Y144800D03*
Y147000D03*
X943400Y144700D03*
Y146900D03*
X946400Y159200D03*
Y161400D03*
G54D18*
X57700Y495800D03*
X53600D03*
X92360Y563310D03*
X110000Y287800D03*
X145000Y458300D03*
X141000D03*
X150150Y449290D03*
X155680Y449230D03*
X146150Y449290D03*
X137000Y457800D03*
X140500Y449290D03*
X164000Y457800D03*
X161500Y498300D03*
X164000Y791800D03*
X160000D03*
X182300Y407900D03*
X193650Y455122D03*
X189650D03*
X197500Y570800D03*
X191500Y581300D03*
X199500Y712800D03*
X171300Y736100D03*
X167300D03*
X199500Y768300D03*
X200500Y408300D03*
X230571Y466317D03*
X221000Y534800D03*
X229000Y518300D03*
X225000Y525800D03*
X229000D03*
X201500Y570800D03*
X203500Y712800D03*
Y768300D03*
X237500Y132300D03*
X245500D03*
X241500D03*
X235100Y462800D03*
X251800Y463000D03*
X274406Y719698D03*
X278406D03*
X286906Y768698D03*
X299164Y768891D03*
X295079Y768650D03*
X303406Y768698D03*
X323406Y767698D03*
X319406D03*
X476200Y377000D03*
X480200D03*
X487906Y771698D03*
X491906D03*
X500406Y820698D03*
X512679Y820650D03*
X508579D03*
X516906Y820698D03*
X524906D03*
X528906D03*
X711510Y10480D03*
X715380Y22080D03*
X715130Y45700D03*
X837000Y774800D03*
X852400Y84100D03*
X871000Y78800D03*
X848100Y84200D03*
X856906Y748698D03*
X860906D03*
X869906Y797698D03*
X893100Y34700D03*
X875000Y89800D03*
X879500D03*
X884000D03*
X888500D03*
X893000D03*
X897500D03*
X902000D03*
X906500D03*
X882049Y800260D03*
X877949D03*
X886276Y800308D03*
X894406Y797698D03*
X898406D03*
X911000Y89800D03*
X915500D03*
X920000D03*
X933500D03*
X929000D03*
X924500D03*
X938000D03*
X956000D03*
X990552Y101100D03*
X986552D03*
X1003100D03*
X999000D03*
X987039Y153815D03*
X1035830Y7519D03*
X1040140Y7563D03*
X1044147Y10390D03*
X1049161Y8407D03*
X1073250Y29050D03*
X1046950Y33165D03*
X1051450D03*
X1068750Y17050D03*
X1065475Y48873D03*
X1061342Y72396D03*
X1293500Y274300D03*
X1302128Y677167D03*
X1306128D03*
X1314628Y726167D03*
X1325500Y726300D03*
X1334128Y726167D03*
X1338128D03*
X1355000Y279800D03*
X1359000D03*
X1351000D03*
G54D36*
X285900Y148900D03*
X307300Y780100D03*
X579234Y243270D03*
X626863Y233108D03*
X700800Y817300D03*
X721887Y201942D03*
X1168407Y823010D03*
X1312300Y271400D03*
X1329500Y817400D03*
G54D46*
X1025679Y31110D03*
Y28550D03*
Y25990D03*
Y23435D03*
X1015079D03*
Y25990D03*
Y28550D03*
Y31110D03*
G54D19*
X67400Y269300D03*
X72100D03*
X228500Y156200D03*
X276200Y154100D03*
G54D37*
X282300Y143300D03*
X632363Y238108D03*
X652600Y788200D03*
X952200Y44100D03*
X1318700Y266500D03*
X1369100Y254500D03*
G54D28*
X105500Y291200D03*
X103500Y461200D03*
X113000Y462200D03*
X185500Y461200D03*
X197800Y447200D03*
X189600Y447100D03*
X193600D03*
X197700Y458035D03*
X177500Y461200D03*
X184500Y548700D03*
X232600Y102000D03*
X210086Y204800D03*
X206076D03*
X202638Y437545D03*
X220838Y435345D03*
X230572Y462313D03*
X201800Y447200D03*
X201700Y458035D03*
X210300Y457500D03*
X214300D03*
X225000Y538200D03*
Y521700D03*
X249995Y102158D03*
X236800Y101900D03*
X251000Y501600D03*
X263000Y755700D03*
X290500Y149200D03*
X295678Y736131D03*
X278050Y736717D03*
X298554Y723113D03*
X286406Y723098D03*
X282406D03*
X290500Y723200D03*
X294506Y723098D03*
X285000Y752200D03*
X267500D03*
X293678Y760131D03*
X289678D03*
X279500Y759700D03*
X282378Y772131D03*
X301000Y747700D03*
X317000Y748200D03*
X311678Y736131D03*
X327678D03*
X310406Y723098D03*
X302554Y723113D03*
X311178Y760131D03*
X307178D03*
X325678D03*
X321678D03*
X495906Y775098D03*
X499906D03*
X498000Y804200D03*
X480800D03*
X502678Y812131D03*
X492500Y811700D03*
X482000D03*
X491900Y788100D03*
X495878Y824131D03*
X521820Y133770D03*
X513820D03*
X525820D03*
X517820D03*
X527000Y774900D03*
X521900Y774800D03*
X517800Y774900D03*
X513700D03*
X509600D03*
X514000Y799200D03*
X530000D03*
X506678Y812131D03*
X520178D03*
X524678Y788131D03*
X534678Y812131D03*
X524178D03*
X570345Y133730D03*
X538678Y812131D03*
X540678Y788131D03*
X542800Y812500D03*
X578467Y133730D03*
X582467D03*
X574345D03*
X584363Y224308D03*
X592363D03*
X588363D03*
X620048Y133944D03*
X612026Y133952D03*
X624048Y133944D03*
X616026Y133952D03*
X659500Y133700D03*
X650500D03*
X655000D03*
X646000D03*
X641963Y238308D03*
X715390Y33080D03*
X720100Y41500D03*
X715130Y56600D03*
X834252Y17700D03*
X820212Y17619D03*
X830252Y17700D03*
X826138Y17004D03*
X838252Y17700D03*
X846252D03*
X873100Y30700D03*
X842252Y17700D03*
X857500Y781700D03*
X841000Y778200D03*
X852400Y765600D03*
X864906Y752098D03*
X868906D03*
X870400Y789100D03*
X844810Y789290D03*
X865378Y801131D03*
X877300Y30700D03*
X906500Y82200D03*
X902000D03*
X897500D03*
X893000D03*
X888500D03*
X875000D03*
X884000D03*
X879500D03*
X882203Y765695D03*
X893406Y752098D03*
X889306D03*
X885306D03*
X881306D03*
X877200Y752000D03*
X887500Y784700D03*
X878600Y788700D03*
X896178Y789131D03*
X892178D03*
X911000Y82200D03*
X915500D03*
X920000D03*
X933500D03*
X929000D03*
X924500D03*
X938000D03*
X951500D03*
Y93200D03*
X947000Y82200D03*
Y93200D03*
X942500Y82200D03*
Y93200D03*
X956000Y82200D03*
X994700Y104500D03*
X1069700Y8000D03*
X1044161Y21268D03*
X1068750Y27950D03*
X1073250Y39950D03*
X1061342Y68394D03*
X1065475Y44273D03*
X1310128Y680567D03*
X1302000Y706700D03*
X1298000Y710700D03*
X1312900Y693600D03*
X1310900Y717100D03*
X1310100Y729600D03*
X1338128Y680567D03*
X1330128D03*
X1326128D03*
X1322128D03*
X1314128D03*
X1319500Y709200D03*
X1336000Y705200D03*
X1330400Y693600D03*
X1329900Y717600D03*
X1325900D03*
X1344900D03*
X1340900D03*
X1346900Y693600D03*
G54D38*
X276700Y143300D03*
X626763Y238108D03*
X647000Y788200D03*
X946600Y44100D03*
X1313100Y266500D03*
X1363500Y254500D03*
G54D29*
X120351Y630236D03*
X126851D03*
X143217Y501760D03*
X156862Y501811D03*
X152916Y501536D03*
X146960Y501630D03*
X165851Y627736D03*
X137551Y625736D03*
X149851Y627736D03*
X155851D03*
X160851D03*
X217000Y538300D03*
X221000Y529300D03*
X500332Y133764D03*
X493245Y133625D03*
X489680Y133605D03*
X503827Y133704D03*
X563002Y137395D03*
X559591D03*
X597044Y133868D03*
X593636D03*
X600522Y133853D03*
X603924D03*
X635500Y349900D03*
X630500D03*
X627000D03*
X639000D03*
X848660Y789290D03*
X1175156Y138119D03*
X1171622Y139828D03*
X1168207Y139826D03*
X1178558Y138118D03*
X1240709Y150353D03*
X1237308D03*
X1269834Y147434D03*
X1266432D03*
X1289500Y277800D03*
G54D47*
X1039500Y50700D03*
G54D39*
X273162Y749719D03*
X275722D03*
X278282D03*
Y743219D03*
X273162D03*
X290440Y749750D03*
X293000D03*
X295560D03*
Y743250D03*
X290440D03*
X306440Y749750D03*
X309000D03*
X311560D03*
Y743250D03*
X306440D03*
X322440Y749750D03*
X325000D03*
X327560D03*
Y743250D03*
X322440D03*
X486662Y801719D03*
X489222D03*
X491782D03*
Y795219D03*
X486662D03*
X535440Y801750D03*
Y795250D03*
X519440Y801750D03*
X522000D03*
X524560D03*
Y795250D03*
X519440D03*
X503440Y801750D03*
X506000D03*
X508560D03*
Y795250D03*
X503440D03*
X538000Y801750D03*
X540560D03*
Y795250D03*
X873060Y37350D03*
X870500D03*
X867940D03*
Y43850D03*
X873060D03*
X862940Y778750D03*
X865500D03*
X868060D03*
Y772250D03*
X862940D03*
X846662Y779219D03*
X849222D03*
X851782D03*
Y772719D03*
X846662D03*
X892940Y778750D03*
X895500D03*
X898060D03*
Y772250D03*
X892940D03*
X876940Y778750D03*
X879500D03*
X882060D03*
Y772250D03*
X876940D03*
X1307662Y706719D03*
X1310222D03*
X1307662Y700219D03*
X1312782Y706719D03*
Y700219D03*
X1341662Y707219D03*
X1344222D03*
X1341662Y700719D03*
X1325162Y707219D03*
X1327722D03*
X1330282D03*
Y700719D03*
X1325162D03*
X1376734Y175745D03*
X1374174D03*
X1371614D03*
Y182245D03*
X1376734D03*
X1346782Y707219D03*
Y700719D03*
G54D48*
X1039500Y56300D03*
G54D49*
X1030000Y50150D03*
X1026125Y57650D03*
X1033875D03*
M02*
